G04 ================== begin FILE IDENTIFICATION RECORD ==================*
G04 Layout Name:  9052_F0T_PDB_Converter_Brick_F_V03_1208_1600.brd*
G04 Film Name:    gnd2*
G04 File Format:  Gerber RS274X*
G04 File Origin:  Cadence Allegro 17.2-S081*
G04 Origin Date:  Wed Dec 21 09:54:59 2022*
G04 *
G04 Layer:  DRAWING FORMAT/TITLE_BLOCK_A*
G04 Layer:  PIN/SPECIAL_DRILL*
G04 Layer:  VIA CLASS/GND2*
G04 Layer:  PIN/GND2*
G04 Layer:  MANUFACTURING/PHOTOPLOT_OUTLINE*
G04 Layer:  ETCH/GND2*
G04 Layer:  DRAWING FORMAT/TITLE_BLOCK*
G04 Layer:  DRAWING FORMAT/TITLE_DATA_GND2*
G04 *
G04 Offset:    (0.00 0.00)*
G04 Mirror:    No*
G04 Mode:      Negative*
G04 Rotation:  0*
G04 FullContactRelief:  No*
G04 UndefLineWidth:     6.00*
G04 ================== end FILE IDENTIFICATION RECORD ====================*
%FSLAX25Y25*MOIN*%
%IR0*IPPOS*OFA0.00000B0.00000*MIA0B0*SFA1.00000B1.00000*%
%ADD20C,.03*%
%AMMACRO12*
4,1,41,.45275,-.05906,
.463006,-.058163,
.47295,-.055498,
.48228,-.051147,
.490713,-.045243,
.497993,-.037963,
.503897,-.02953,
.508248,-.0202,
.510913,-.010256,
.51181,0.0,
.510913,.010256,
.508248,.0202,
.503897,.02953,
.497993,.037963,
.490713,.045243,
.48228,.051147,
.47295,.055498,
.463006,.058163,
.45275,.05906,
.33464,.05906,
-.4082,.09829,
-.425347,.097699,
-.442131,.09414,
-.458041,.08772,
-.472595,.078635,
-.485351,.06716,
-.49592,.053645,
-.503981,.0385,
-.509291,.022185,
-.511686,.005196,
-.511095,-.011951,
-.507536,-.028734,
-.501116,-.044645,
-.492031,-.059199,
-.480557,-.071954,
-.467041,-.082523,
-.451896,-.090585,
-.435582,-.095894,
-.418593,-.09829,
-.4082,-.09829,
.33464,-.05906,
.45275,-.05906,
0.0*
%
%ADD12MACRO12*%
%ADD35C,.06*%
%ADD16C,.061*%
%ADD28C,.062*%
%ADD25C,.026*%
%ADD17C,.054*%
%AMMACRO27*
4,1,36,.0025,0.0,
.002462,.000434,
.002349,.000855,
.002165,.00125,
.001915,.001607,
.001607,.001915,
.00125,.002165,
.000855,.002349,
.000434,.002462,
0.0,.0025,
-.000434,.002462,
-.000855,.002349,
-.00125,.002165,
-.001607,.001915,
-.001915,.001607,
-.002165,.00125,
-.002349,.000855,
-.002462,.000434,
-.0025,0.0,
-.002462,-.000434,
-.002349,-.000855,
-.002165,-.00125,
-.001915,-.001607,
-.001607,-.001915,
-.00125,-.002165,
-.000855,-.002349,
-.000434,-.002462,
0.0,-.0025,
.000434,-.002462,
.000855,-.002349,
.00125,-.002165,
.001607,-.001915,
.001915,-.001607,
.002165,-.00125,
.002349,-.000855,
.002462,-.000434,
.0025,0.0,
180.*
%
%ADD27MACRO27*%
%AMMACRO23*
4,1,36,.0025,0.0,
.002462,.000434,
.002349,.000855,
.002165,.00125,
.001915,.001607,
.001607,.001915,
.00125,.002165,
.000855,.002349,
.000434,.002462,
0.0,.0025,
-.000434,.002462,
-.000855,.002349,
-.00125,.002165,
-.001607,.001915,
-.001915,.001607,
-.002165,.00125,
-.002349,.000855,
-.002462,.000434,
-.0025,0.0,
-.002462,-.000434,
-.002349,-.000855,
-.002165,-.00125,
-.001915,-.001607,
-.001607,-.001915,
-.00125,-.002165,
-.000855,-.002349,
-.000434,-.002462,
0.0,-.0025,
.000434,-.002462,
.000855,-.002349,
.00125,-.002165,
.001607,-.001915,
.001915,-.001607,
.002165,-.00125,
.002349,-.000855,
.002462,-.000434,
.0025,0.0,
270.*
%
%ADD23MACRO23*%
%ADD33C,.083*%
%ADD30C,.056*%
%ADD43C,.066*%
%ADD38C,.06015*%
%ADD40C,.087*%
%AMMACRO37*
4,1,36,0.0,.019,
-.003299,.018711,
-.006498,.017854,
-.0095,.016454,
-.012213,.014555,
-.014555,.012213,
-.016454,.0095,
-.017854,.006498,
-.018711,.003299,
-.019,0.0,
-.018711,-.003299,
-.017854,-.006498,
-.016454,-.0095,
-.014555,-.012213,
-.012213,-.014555,
-.0095,-.016454,
-.006498,-.017854,
-.003299,-.018711,
0.0,-.019,
.003299,-.018711,
.006498,-.017854,
.0095,-.016454,
.012213,-.014555,
.014555,-.012213,
.016454,-.0095,
.017854,-.006498,
.018711,-.003299,
.019,0.0,
.018711,.003299,
.017854,.006498,
.016454,.0095,
.014555,.012213,
.012213,.014555,
.0095,.016454,
.006498,.017854,
.003299,.018711,
0.0,.019,
0.0*
%
%ADD37MACRO37*%
%AMMACRO26*
4,1,16,.04271,.02503,
.046408,.017233,
.048695,.008913,
.049503,.000322,
.048807,-.008279,
.046628,-.016629,
.043032,-.024473,
.04271,-.02503,
.0478,-.03012,
.052304,-.021362,
.055219,-.011955,
.056456,-.002185,
.055978,.007652,
.053799,.017256,
.049985,.026336,
.0478,.03012,
.04271,.02503,
270.*
4,1,16,.02503,-.04271,
.017233,-.046408,
.008913,-.048695,
.000322,-.049503,
-.008279,-.048807,
-.016629,-.046628,
-.024473,-.043032,
-.02503,-.04271,
-.03012,-.0478,
-.021362,-.052304,
-.011955,-.055219,
-.002185,-.056456,
.007652,-.055978,
.017256,-.053799,
.026336,-.049985,
.03012,-.0478,
.02503,-.04271,
270.*
4,1,16,-.04271,-.02503,
-.046408,-.017233,
-.048695,-.008913,
-.049503,-.000322,
-.048807,.008279,
-.046628,.016629,
-.043032,.024473,
-.04271,.02503,
-.0478,.03012,
-.052304,.021362,
-.055219,.011955,
-.056456,.002185,
-.055978,-.007652,
-.053799,-.017256,
-.049985,-.026336,
-.0478,-.03012,
-.04271,-.02503,
270.*
4,1,16,-.02503,.04271,
-.017233,.046408,
-.008913,.048695,
-.000322,.049503,
.008279,.048807,
.016629,.046628,
.024473,.043032,
.02503,.04271,
.03012,.0478,
.021362,.052304,
.011955,.055219,
.002185,.056456,
-.007652,.055978,
-.017256,.053799,
-.026336,.049985,
-.03012,.0478,
-.02503,.04271,
270.*
%
%ADD26MACRO26*%
%AMMACRO44*
4,1,16,.02657,.01597,
.02894,.011114,
.03043,.005919,
.030995,.000545,
.030619,-.004845,
.029313,-.010088,
.027115,-.015025,
.02657,-.01597,
.03164,-.02104,
.034813,-.015226,
.036928,-.00895,
.037921,-.002401,
.037762,.00422,
.036455,.010713,
.034041,.016881,
.03164,.02104,
.02657,.01597,
90.*
4,1,16,.01597,-.02657,
.011114,-.02894,
.005919,-.03043,
.000545,-.030995,
-.004845,-.030619,
-.010088,-.029313,
-.015025,-.027115,
-.01597,-.02657,
-.02104,-.03164,
-.015226,-.034813,
-.00895,-.036928,
-.002401,-.037921,
.00422,-.037762,
.010713,-.036455,
.016881,-.034041,
.02104,-.03164,
.01597,-.02657,
90.*
4,1,16,-.02657,-.01597,
-.02894,-.011114,
-.03043,-.005919,
-.030995,-.000545,
-.030619,.004845,
-.029313,.010088,
-.027115,.015025,
-.02657,.01597,
-.03164,.02104,
-.034813,.015226,
-.036928,.00895,
-.037921,.002401,
-.037762,-.00422,
-.036455,-.010713,
-.034041,-.016881,
-.03164,-.02104,
-.02657,-.01597,
90.*
4,1,16,-.01597,.02657,
-.011114,.02894,
-.005919,.03043,
-.000545,.030995,
.004845,.030619,
.010088,.029313,
.015025,.027115,
.01597,.02657,
.02104,.03164,
.015226,.034813,
.00895,.036928,
.002401,.037921,
-.00422,.037762,
-.010713,.036455,
-.016881,.034041,
-.02104,.03164,
-.01597,.02657,
90.*
%
%ADD44MACRO44*%
%AMMACRO29*
4,1,16,.02511,.01451,
.027248,.009929,
.028558,.005047,
.029001,.000011,
.028562,-.005025,
.027256,-.009909,
.025121,-.014491,
.02511,-.01451,
.0302,-.01959,
.033143,-.014048,
.035079,-.00808,
.035949,-.001865,
.035727,.004405,
.034419,.010542,
.032065,.016359,
.0302,.01959,
.02511,.01451,
0.0*
4,1,16,.01451,-.02511,
.009929,-.027248,
.005047,-.028558,
.000011,-.029001,
-.005025,-.028562,
-.009909,-.027256,
-.014491,-.025121,
-.01451,-.02511,
-.01959,-.0302,
-.014048,-.033143,
-.00808,-.035079,
-.001865,-.035949,
.004405,-.035727,
.010542,-.034419,
.016359,-.032065,
.01959,-.0302,
.01451,-.02511,
0.0*
4,1,16,-.02511,-.01451,
-.027248,-.009929,
-.028558,-.005047,
-.029001,-.000011,
-.028562,.005025,
-.027256,.009909,
-.025121,.014491,
-.02511,.01451,
-.0302,.01959,
-.033143,.014048,
-.035079,.00808,
-.035949,.001865,
-.035727,-.004405,
-.034419,-.010542,
-.032065,-.016359,
-.0302,-.01959,
-.02511,-.01451,
0.0*
4,1,16,-.01451,.02511,
-.009929,.027248,
-.005047,.028558,
-.000011,.029001,
.005025,.028562,
.009909,.027256,
.014491,.025121,
.01451,.02511,
.01959,.0302,
.014048,.033143,
.00808,.035079,
.001865,.035949,
-.004405,.035727,
-.010542,.034419,
-.016359,.032065,
-.01959,.0302,
-.01451,.02511,
0.0*
%
%ADD29MACRO29*%
%AMMACRO46*
4,1,15,.03682,.01914,
.039584,.012455,
.041146,.005393,
.041457,-.001834,
.040509,-.009005,
.03833,-.015903,
.03682,-.01914,
.04197,-.0243,
.045552,-.016643,
.04775,-.00848,
.048497,-.000059,
.047771,.008363,
.045593,.016531,
.042029,.024197,
.04197,.0243,
.03682,.01914,
90.*
4,1,15,.01914,-.03682,
.012455,-.039584,
.005393,-.041146,
-.001834,-.041457,
-.009005,-.040509,
-.015903,-.03833,
-.01914,-.03682,
-.0243,-.04197,
-.016643,-.045552,
-.00848,-.04775,
-.000059,-.048497,
.008363,-.047771,
.016531,-.045593,
.024197,-.042029,
.0243,-.04197,
.01914,-.03682,
90.*
4,1,15,-.03682,-.01914,
-.039584,-.012455,
-.041146,-.005393,
-.041457,.001834,
-.040509,.009005,
-.03833,.015903,
-.03682,.01914,
-.04197,.0243,
-.045552,.016643,
-.04775,.00848,
-.048497,.000059,
-.047771,-.008363,
-.045593,-.016531,
-.042029,-.024197,
-.04197,-.0243,
-.03682,-.01914,
90.*
4,1,15,-.01914,.03682,
-.012455,.039584,
-.005393,.041146,
.001834,.041457,
.009005,.040509,
.015903,.03833,
.01914,.03682,
.0243,.04197,
.016643,.045552,
.00848,.04775,
.000059,.048497,
-.008363,.047771,
-.016531,.045593,
-.024197,.042029,
-.0243,.04197,
-.01914,.03682,
90.*
%
%ADD46MACRO46*%
%AMMACRO45*
4,1,15,-.03682,.01914,
-.039584,.012455,
-.041146,.005393,
-.041457,-.001834,
-.040509,-.009005,
-.03833,-.015903,
-.03682,-.01914,
-.04197,-.0243,
-.045552,-.016643,
-.04775,-.00848,
-.048497,-.000059,
-.047771,.008363,
-.045593,.016531,
-.042029,.024197,
-.04197,.0243,
-.03682,.01914,
90.*
4,1,15,-.01914,-.03682,
-.012455,-.039584,
-.005393,-.041146,
.001834,-.041457,
.009005,-.040509,
.015903,-.03833,
.01914,-.03682,
.0243,-.04197,
.016643,-.045552,
.00848,-.04775,
.000059,-.048497,
-.008363,-.047771,
-.016531,-.045593,
-.024197,-.042029,
-.0243,-.04197,
-.01914,-.03682,
90.*
4,1,15,.03682,-.01914,
.039584,-.012455,
.041146,-.005393,
.041457,.001834,
.040509,.009005,
.03833,.015903,
.03682,.01914,
.04197,.0243,
.045552,.016643,
.04775,.00848,
.048497,.000059,
.047771,-.008363,
.045593,-.016531,
.042029,-.024197,
.04197,-.0243,
.03682,-.01914,
90.*
4,1,15,.01914,.03682,
.012455,.039584,
.005393,.041146,
-.001834,.041457,
-.009005,.040509,
-.015903,.03833,
-.01914,.03682,
-.0243,.04197,
-.016643,.045552,
-.00848,.04775,
-.000059,.048497,
.008363,.047771,
.016531,.045593,
.024197,.042029,
.0243,.04197,
.01914,.03682,
90.*
%
%ADD45MACRO45*%
%ADD36C,.103*%
%AMMACRO13*
4,1,36,0.0,.005,
.000868,.004924,
.00171,.004698,
.0025,.00433,
.003214,.00383,
.00383,.003214,
.00433,.0025,
.004698,.00171,
.004924,.000868,
.005,0.0,
.004924,-.000868,
.004698,-.00171,
.00433,-.0025,
.00383,-.003214,
.003214,-.00383,
.0025,-.00433,
.00171,-.004698,
.000868,-.004924,
0.0,-.005,
-.000868,-.004924,
-.00171,-.004698,
-.0025,-.00433,
-.003214,-.00383,
-.00383,-.003214,
-.00433,-.0025,
-.004698,-.00171,
-.004924,-.000868,
-.005,0.0,
-.004924,.000868,
-.004698,.00171,
-.00433,.0025,
-.00383,.003214,
-.003214,.00383,
-.0025,.00433,
-.00171,.004698,
-.000868,.004924,
0.0,.005,
270.*
%
%ADD13MACRO13*%
%ADD11C,.125*%
%ADD14C,.117*%
%ADD24C,.155*%
%ADD21C,.237*%
%ADD32C,.256*%
%AMMACRO22*
4,1,36,.0025,0.0,
.002462,.000434,
.002349,.000855,
.002165,.00125,
.001915,.001607,
.001607,.001915,
.00125,.002165,
.000855,.002349,
.000434,.002462,
0.0,.0025,
-.000434,.002462,
-.000855,.002349,
-.00125,.002165,
-.001607,.001915,
-.001915,.001607,
-.002165,.00125,
-.002349,.000855,
-.002462,.000434,
-.0025,0.0,
-.002462,-.000434,
-.002349,-.000855,
-.002165,-.00125,
-.001915,-.001607,
-.001607,-.001915,
-.00125,-.002165,
-.000855,-.002349,
-.000434,-.002462,
0.0,-.0025,
.000434,-.002462,
.000855,-.002349,
.00125,-.002165,
.001607,-.001915,
.001915,-.001607,
.002165,-.00125,
.002349,-.000855,
.002462,-.000434,
.0025,0.0,
90.*
%
%ADD22MACRO22*%
%ADD19C,.186*%
%ADD48C,.187*%
%AMMACRO42*
4,1,36,0.0,.019,
-.003299,.018711,
-.006498,.017854,
-.0095,.016454,
-.012213,.014555,
-.014555,.012213,
-.016454,.0095,
-.017854,.006498,
-.018711,.003299,
-.019,0.0,
-.018711,-.003299,
-.017854,-.006498,
-.016454,-.0095,
-.014555,-.012213,
-.012213,-.014555,
-.0095,-.016454,
-.006498,-.017854,
-.003299,-.018711,
0.0,-.019,
.003299,-.018711,
.006498,-.017854,
.0095,-.016454,
.012213,-.014555,
.014555,-.012213,
.016454,-.0095,
.017854,-.006498,
.018711,-.003299,
.019,0.0,
.018711,.003299,
.017854,.006498,
.016454,.0095,
.014555,.012213,
.012213,.014555,
.0095,.016454,
.006498,.017854,
.003299,.018711,
0.0,.019,
270.*
%
%ADD42MACRO42*%
%AMMACRO10*
4,1,36,.0025,0.0,
.002462,.000434,
.002349,.000855,
.002165,.00125,
.001915,.001607,
.001607,.001915,
.00125,.002165,
.000855,.002349,
.000434,.002462,
0.0,.0025,
-.000434,.002462,
-.000855,.002349,
-.00125,.002165,
-.001607,.001915,
-.001915,.001607,
-.002165,.00125,
-.002349,.000855,
-.002462,.000434,
-.0025,0.0,
-.002462,-.000434,
-.002349,-.000855,
-.002165,-.00125,
-.001915,-.001607,
-.001607,-.001915,
-.00125,-.002165,
-.000855,-.002349,
-.000434,-.002462,
0.0,-.0025,
.000434,-.002462,
.000855,-.002349,
.00125,-.002165,
.001607,-.001915,
.001915,-.001607,
.002165,-.00125,
.002349,-.000855,
.002462,-.000434,
.0025,0.0,
0.0*
%
%ADD10MACRO10*%
%AMMACRO18*
4,1,15,.02217,.01156,
.023841,.007535,
.024787,.00328,
.02498,-.001074,
.024414,-.005395,
.023106,-.009553,
.02217,-.01156,
.0273,-.01669,
.029783,-.011696,
.031362,-.006346,
.031987,-.000804,
.031641,.004763,
.030333,.010185,
.028104,.015297,
.0273,.01669,
.02217,.01156,
270.*
4,1,15,.01156,-.02217,
.007535,-.023841,
.00328,-.024787,
-.001074,-.02498,
-.005395,-.024414,
-.009553,-.023106,
-.01156,-.02217,
-.01669,-.0273,
-.011696,-.029783,
-.006346,-.031362,
-.000804,-.031987,
.004763,-.031641,
.010185,-.030333,
.015297,-.028104,
.01669,-.0273,
.01156,-.02217,
270.*
4,1,15,-.02217,-.01156,
-.023841,-.007535,
-.024787,-.00328,
-.02498,.001074,
-.024414,.005395,
-.023106,.009553,
-.02217,.01156,
-.0273,.01669,
-.029783,.011696,
-.031362,.006346,
-.031987,.000804,
-.031641,-.004763,
-.030333,-.010185,
-.028104,-.015297,
-.0273,-.01669,
-.02217,-.01156,
270.*
4,1,15,-.01156,.02217,
-.007535,.023841,
-.00328,.024787,
.001074,.02498,
.005395,.024414,
.009553,.023106,
.01156,.02217,
.01669,.0273,
.011696,.029783,
.006346,.031362,
.000804,.031987,
-.004763,.031641,
-.010185,.030333,
-.015297,.028104,
-.01669,.0273,
-.01156,.02217,
270.*
%
%ADD18MACRO18*%
%AMMACRO34*
4,1,15,.02438,.01377,
.026401,.009327,
.027619,.004601,
.027999,-.000265,
.027527,-.005123,
.02622,-.009825,
.02438,-.01377,
.02948,-.01887,
.032309,-.013464,
.034156,-.007649,
.034965,-.001602,
.034712,.004494,
.033405,.010454,
.031082,.016095,
.02948,.01887,
.02438,.01377,
270.*
4,1,15,.01377,-.02438,
.009327,-.026401,
.004601,-.027619,
-.000265,-.027999,
-.005123,-.027527,
-.009825,-.02622,
-.01377,-.02438,
-.01887,-.02948,
-.013464,-.032309,
-.007649,-.034156,
-.001602,-.034965,
.004494,-.034712,
.010454,-.033405,
.016095,-.031082,
.01887,-.02948,
.01377,-.02438,
270.*
4,1,15,-.02438,-.01377,
-.026401,-.009327,
-.027619,-.004601,
-.027999,.000265,
-.027527,.005123,
-.02622,.009825,
-.02438,.01377,
-.02948,.01887,
-.032309,.013464,
-.034156,.007649,
-.034965,.001602,
-.034712,-.004494,
-.033405,-.010454,
-.031082,-.016095,
-.02948,-.01887,
-.02438,-.01377,
270.*
4,1,15,-.01377,.02438,
-.009327,.026401,
-.004601,.027619,
.000265,.027999,
.005123,.027527,
.009825,.02622,
.01377,.02438,
.01887,.02948,
.013464,.032309,
.007649,.034156,
.001602,.034965,
-.004494,.034712,
-.010454,.033405,
-.016095,.031082,
-.01887,.02948,
-.01377,.02438,
270.*
%
%ADD34MACRO34*%
%AMMACRO15*
4,1,15,.02475,.01414,
.026829,.009627,
.028094,.004822,
.028504,-.000129,
.028049,-.005077,
.026741,-.009871,
.02475,-.01414,
.02984,-.01923,
.032726,-.013756,
.034617,-.007864,
.035457,-.001734,
.03522,.00445,
.033912,.010498,
.031574,.016227,
.02984,.01923,
.02475,.01414,
270.*
4,1,15,.01414,-.02475,
.009627,-.026829,
.004822,-.028094,
-.000129,-.028504,
-.005077,-.028049,
-.009871,-.026741,
-.01414,-.02475,
-.01923,-.02984,
-.013756,-.032726,
-.007864,-.034617,
-.001734,-.035457,
.00445,-.03522,
.010498,-.033912,
.016227,-.031574,
.01923,-.02984,
.01414,-.02475,
270.*
4,1,15,-.02475,-.01414,
-.026829,-.009627,
-.028094,-.004822,
-.028504,.000129,
-.028049,.005077,
-.026741,.009871,
-.02475,.01414,
-.02984,.01923,
-.032726,.013756,
-.034617,.007864,
-.035457,.001734,
-.03522,-.00445,
-.033912,-.010498,
-.031574,-.016227,
-.02984,-.01923,
-.02475,-.01414,
270.*
4,1,15,-.01414,.02475,
-.009627,.026829,
-.004822,.028094,
.000129,.028504,
.005077,.028049,
.009871,.026741,
.01414,.02475,
.01923,.02984,
.013756,.032726,
.007864,.034617,
.001734,.035457,
-.00445,.03522,
-.010498,.033912,
-.016227,.031574,
-.01923,.02984,
-.01414,.02475,
270.*
%
%ADD15MACRO15*%
%AMMACRO47*
4,1,18,.10783,.07955,
.120006,.059617,
.128535,.037873,
.133159,.014977,
.133736,-.008373,
.130251,-.031469,
.122807,-.053609,
.111633,-.074119,
.10783,-.07955,
.11284,-.08455,
.125808,-.063671,
.134953,-.040857,
.139997,-.016802,
.140788,.007763,
.137301,.032093,
.129642,.055447,
.118045,.077117,
.11284,.08455,
.10783,.07955,
270.*
4,1,18,.07955,-.10783,
.059617,-.120006,
.037873,-.128535,
.014977,-.133159,
-.008373,-.133736,
-.031469,-.130251,
-.053609,-.122807,
-.074119,-.111633,
-.07955,-.10783,
-.08455,-.11284,
-.063671,-.125808,
-.040857,-.134953,
-.016802,-.139997,
.007763,-.140788,
.032093,-.137301,
.055447,-.129642,
.077117,-.118045,
.08455,-.11284,
.07955,-.10783,
270.*
4,1,18,-.10783,-.07955,
-.120006,-.059617,
-.128535,-.037873,
-.133159,-.014977,
-.133736,.008373,
-.130251,.031469,
-.122807,.053609,
-.111633,.074119,
-.10783,.07955,
-.11284,.08455,
-.125808,.063671,
-.134953,.040857,
-.139997,.016802,
-.140788,-.007763,
-.137301,-.032093,
-.129642,-.055447,
-.118045,-.077117,
-.11284,-.08455,
-.10783,-.07955,
270.*
4,1,18,-.07955,.10783,
-.059617,.120006,
-.037873,.128535,
-.014977,.133159,
.008373,.133736,
.031469,.130251,
.053609,.122807,
.074119,.111633,
.07955,.10783,
.08455,.11284,
.063671,.125808,
.040857,.134953,
.016802,.139997,
-.007763,.140788,
-.032093,.137301,
-.055447,.129642,
-.077117,.118045,
-.08455,.11284,
-.07955,.10783,
270.*
%
%ADD47MACRO47*%
%AMMACRO39*
4,1,15,.03682,.01914,
.039584,.012455,
.041146,.005393,
.041457,-.001834,
.040509,-.009005,
.03833,-.015903,
.03682,-.01914,
.04197,-.0243,
.045552,-.016643,
.04775,-.00848,
.048497,-.000059,
.047771,.008363,
.045593,.016531,
.042029,.024197,
.04197,.0243,
.03682,.01914,
270.*
4,1,15,.01914,-.03682,
.012455,-.039584,
.005393,-.041146,
-.001834,-.041457,
-.009005,-.040509,
-.015903,-.03833,
-.01914,-.03682,
-.0243,-.04197,
-.016643,-.045552,
-.00848,-.04775,
-.000059,-.048497,
.008363,-.047771,
.016531,-.045593,
.024197,-.042029,
.0243,-.04197,
.01914,-.03682,
270.*
4,1,15,-.03682,-.01914,
-.039584,-.012455,
-.041146,-.005393,
-.041457,.001834,
-.040509,.009005,
-.03833,.015903,
-.03682,.01914,
-.04197,.0243,
-.045552,.016643,
-.04775,.00848,
-.048497,.000059,
-.047771,-.008363,
-.045593,-.016531,
-.042029,-.024197,
-.04197,-.0243,
-.03682,-.01914,
270.*
4,1,15,-.01914,.03682,
-.012455,.039584,
-.005393,.041146,
.001834,.041457,
.009005,.040509,
.015903,.03833,
.01914,.03682,
.0243,.04197,
.016643,.045552,
.00848,.04775,
.000059,.048497,
-.008363,.047771,
-.016531,.045593,
-.024197,.042029,
-.0243,.04197,
-.01914,.03682,
270.*
%
%ADD39MACRO39*%
%AMMACRO31*
4,1,17,.03273,.02212,
.036074,.0161,
.038322,.009592,
.039405,.002791,
.039291,-.004094,
.037983,-.010854,
.035521,-.017285,
.03273,-.02212,
.03775,-.02715,
.041891,-.020182,
.044759,-.012601,
.046267,-.004638,
.04637,.003467,
.045063,.011466,
.042388,.019117,
.038424,.026188,
.03775,.02715,
.03273,.02212,
270.*
4,1,17,.02212,-.03273,
.0161,-.036074,
.009592,-.038322,
.002791,-.039405,
-.004094,-.039291,
-.010854,-.037983,
-.017285,-.035521,
-.02212,-.03273,
-.02715,-.03775,
-.020182,-.041891,
-.012601,-.044759,
-.004638,-.046267,
.003467,-.04637,
.011466,-.045063,
.019117,-.042388,
.026188,-.038424,
.02715,-.03775,
.02212,-.03273,
270.*
4,1,17,-.03273,-.02212,
-.036074,-.0161,
-.038322,-.009592,
-.039405,-.002791,
-.039291,.004094,
-.037983,.010854,
-.035521,.017285,
-.03273,.02212,
-.03775,.02715,
-.041891,.020182,
-.044759,.012601,
-.046267,.004638,
-.04637,-.003467,
-.045063,-.011466,
-.042388,-.019117,
-.038424,-.026188,
-.03775,-.02715,
-.03273,-.02212,
270.*
4,1,17,-.02212,.03273,
-.0161,.036074,
-.009592,.038322,
-.002791,.039405,
.004094,.039291,
.010854,.037983,
.017285,.035521,
.02212,.03273,
.02715,.03775,
.020182,.041891,
.012601,.044759,
.004638,.046267,
-.003467,.04637,
-.011466,.045063,
-.019117,.042388,
-.026188,.038424,
-.02715,.03775,
-.02212,.03273,
270.*
%
%ADD31MACRO31*%
%AMMACRO41*
4,1,15,-.03682,.01914,
-.039584,.012455,
-.041146,.005393,
-.041457,-.001834,
-.040509,-.009005,
-.03833,-.015903,
-.03682,-.01914,
-.04197,-.0243,
-.045552,-.016643,
-.04775,-.00848,
-.048497,-.000059,
-.047771,.008363,
-.045593,.016531,
-.042029,.024197,
-.04197,.0243,
-.03682,.01914,
270.*
4,1,15,-.01914,-.03682,
-.012455,-.039584,
-.005393,-.041146,
.001834,-.041457,
.009005,-.040509,
.015903,-.03833,
.01914,-.03682,
.0243,-.04197,
.016643,-.045552,
.00848,-.04775,
.000059,-.048497,
-.008363,-.047771,
-.016531,-.045593,
-.024197,-.042029,
-.0243,-.04197,
-.01914,-.03682,
270.*
4,1,15,.03682,-.01914,
.039584,-.012455,
.041146,-.005393,
.041457,.001834,
.040509,.009005,
.03833,.015903,
.03682,.01914,
.04197,.0243,
.045552,.016643,
.04775,.00848,
.048497,.000059,
.047771,-.008363,
.045593,-.016531,
.042029,-.024197,
.04197,-.0243,
.03682,-.01914,
270.*
4,1,15,.01914,.03682,
.012455,.039584,
.005393,.041146,
-.001834,.041457,
-.009005,.040509,
-.015903,.03833,
-.01914,.03682,
-.0243,.04197,
-.016643,.045552,
-.00848,.04775,
-.000059,.048497,
.008363,.047771,
.016531,.045593,
.024197,.042029,
.0243,.04197,
.01914,.03682,
270.*
%
%ADD41MACRO41*%
%ADD49C,.02*%
%ADD50C,.006*%
%ADD55C,.07006*%
%ADD59C,.11022*%
%ADD60C,.10006*%
%ADD57C,.11006*%
%ADD56C,.11206*%
%ADD58C,.14306*%
%ADD52C,.12707*%
%ADD53C,.16506*%
%ADD54C,.19606*%
%ADD51C,.28606*%
%ADD61C,.32598*%
G75*
%LPD*%
G75*
G36*
G01X-297025Y-1013390D02*
X3691357D01*
Y1828909D01*
X-297025D01*
Y-1013390D01*
G37*
%LPC*%
G75*
G36*
G01X1048555Y576740D02*
X1049868D01*
Y576736D01*
X1271654D01*
G02X1289335Y559055I0J-17681D01*
G01Y19685D01*
G02X1271654Y2004I-17681J0D01*
G01X19685D01*
G02X2004Y19685I0J17681D01*
G01Y63268D01*
G02X11811Y73075I9807J0D01*
G01X37796D01*
G03X41768Y77047I0J3973D01*
G01Y122323D01*
G03X37796Y126295I-3973J-1D01*
G01X11811D01*
G02X2004Y136102I0J9807D01*
G01Y445787D01*
G02X11811Y455594I9807J0D01*
G01X37795D01*
G03X41768Y459567I0J3973D01*
G01Y504843D01*
G03X37796Y508815I-3973J-1D01*
G01X11811D01*
G02X2004Y518622I0J9807D01*
G01Y559055D01*
G02X19685Y576736I17681J0D01*
G01X1048555D01*
Y576740D01*
G37*
G36*
G01X1283465Y654614D02*
G02X1289339Y648740I0J-5874D01*
G01Y594488D01*
G02X1283465Y588614I-5874J0D01*
G01X607874D01*
G02X602000Y594488I0J5874D01*
G01Y648740D01*
G02X607874Y654614I5874J0D01*
G01X1283465D01*
G37*
%LPD*%
G75*
G36*
G01X1099239Y524880D02*
G02X1100653Y525466I1414J-1413D01*
G01X1175329D01*
G02X1176743Y524880I0J-1999D01*
G01X1181585Y520038D01*
G02X1182171Y518624I-1413J-1414D01*
G01Y497840D01*
G03X1182230Y497698I200J0D01*
G01X1196769Y483159D01*
G03X1196911Y483100I142J141D01*
G01X1258400D01*
G02X1259814Y482514I0J-1999D01*
G01X1264914Y477414D01*
G02X1265500Y476000I-1413J-1414D01*
G01Y302600D01*
G02X1264914Y301186I-1999J0D01*
G01X1260814Y297086D01*
G02X1259400Y296500I-1414J1413D01*
G01X1216111D01*
G03X1215969Y296441I0J-200D01*
G01X1207639Y288111D01*
G02X1206225Y287525I-1414J1413D01*
G01X1183661D01*
G03X1183519Y287466I0J-200D01*
G01X1182230Y286177D01*
G03X1182171Y286035I141J-142D01*
G01Y239982D01*
G02X1181585Y238568I-1999J0D01*
G01X1176710Y233693D01*
G02X1175296Y233107I-1414J1413D01*
G01X1100979D01*
G02X1099565Y233693I0J1999D01*
G01X1093861Y239397D01*
G02X1093275Y240811I1413J1414D01*
G01Y518088D01*
G02X1093861Y519502I1999J0D01*
G01X1099239Y524880D01*
G37*
G36*
G01X637793Y40521D02*
G02X634698Y44000I408J3479D01*
G02X634903Y45182I3502J1D01*
G03Y45318I-188J68D01*
G02X634698Y46500I3297J1181D01*
G02X638058Y50000I3503J0D01*
G03X638215Y50086I-7J200D01*
G02X641100Y51602I2885J-1987D01*
G02X644602Y48100I0J-3502D01*
G02X643351Y45417I-3503J0D01*
G01X643318Y45389D01*
X643281Y45313D01*
X643268Y44930D01*
X643299Y44852D01*
X643330Y44822D01*
G02X644402Y42300I-2431J-2522D01*
G02X640900Y38798I-3502J0D01*
G02X637939Y40429I0J3503D01*
G03X637793Y40521I-169J-107D01*
G37*
G36*
G01X1075308Y93848D02*
G02X1077200Y94402I1890J-2948D01*
G02Y87398I0J-3502D01*
G02X1075308Y87952I-2J3502D01*
G03X1075092I-108J-168D01*
G02X1073200Y87398I-1890J2948D01*
G02Y94402I0J3502D01*
G02X1075092Y93848I2J-3502D01*
G03X1075308I108J168D01*
G37*
G36*
G01X68400Y93092D02*
X67972Y93157D01*
X67879Y93125D01*
X67844Y93087D01*
G02Y106361I-7214J6637D01*
G01X67879Y106323D01*
X67972Y106291D01*
X68400Y106356D01*
X68479Y106415D01*
X68500Y106461D01*
G02X82795Y115526I14295J-6739D01*
G02Y83922I0J-15802D01*
G02X68500Y92987I0J15804D01*
G01X68479Y93033D01*
X68400Y93092D01*
G37*
G36*
G01X1128569Y123243D02*
X1128931D01*
X1129003Y123273D01*
X1129032Y123301D01*
G02X1131500Y124318I2468J-2486D01*
G02X1132919Y124018I1J-3502D01*
G03X1133081I81J183D01*
G02X1134500Y124318I1418J-3202D01*
G02Y117314I0J-3502D01*
G02X1133081Y117614I-1J3502D01*
G03X1132919I-81J-183D01*
G02X1131500Y117314I-1418J3202D01*
G02X1129032Y118331I0J3503D01*
G01X1129003Y118359D01*
X1128931Y118389D01*
X1128569D01*
X1128497Y118359D01*
X1128468Y118331D01*
G02X1126000Y117314I-2468J2486D01*
G02X1124581Y117614I-1J3502D01*
G03X1124419I-81J-183D01*
G02X1123000Y117314I-1418J3202D01*
G02Y124318I0J3502D01*
G02X1124419Y124018I1J-3502D01*
G03X1124581I81J183D01*
G02X1126000Y124318I1418J-3202D01*
G02X1128468Y123301I0J-3503D01*
G01X1128497Y123273D01*
X1128569Y123243D01*
G37*
G36*
G01X1114049Y129633D02*
G02X1115801Y130102I1751J-3033D01*
G02Y123098I0J-3502D01*
G02X1114049Y123567I-1J3502D01*
G02Y129633I1751J3033D01*
G37*
G36*
G01X709714Y144186D02*
Y144630D01*
X709665Y144718D01*
X709621Y144746D01*
G02X707048Y149408I2937J4662D01*
G02X712559Y154918I5511J-1D01*
G02X717221Y152346I0J-5511D01*
G01X717249Y152302D01*
X717337Y152253D01*
X717781D01*
X717869Y152302D01*
X717897Y152346D01*
G02X722559Y154918I4662J-2939D01*
G02X728070Y149408I1J-5510D01*
G02X725497Y144746I-5510J0D01*
G01X725453Y144718D01*
X725404Y144630D01*
Y144186D01*
X725453Y144098D01*
X725497Y144070D01*
G02Y134746I-2937J-4662D01*
G01X725453Y134718D01*
X725404Y134630D01*
Y134186D01*
X725453Y134098D01*
X725497Y134070D01*
G02Y124746I-2937J-4662D01*
G01X725453Y124718D01*
X725404Y124630D01*
Y124186D01*
X725453Y124098D01*
X725497Y124070D01*
G02X728070Y119408I-2937J-4662D01*
G02X722559Y113898I-5511J1D01*
G02X717897Y116470I0J5511D01*
G01X717869Y116514D01*
X717781Y116563D01*
X717337D01*
X717249Y116514D01*
X717221Y116470D01*
G02X712559Y113898I-4662J2939D01*
G02X707048Y119408I-1J5510D01*
G02X709621Y124070I5510J0D01*
G01X709665Y124098D01*
X709714Y124186D01*
Y124630D01*
X709665Y124718D01*
X709621Y124746D01*
G02Y134070I2937J4662D01*
G01X709665Y134098D01*
X709714Y134186D01*
Y134630D01*
X709665Y134718D01*
X709621Y134746D01*
G02Y144070I2937J4662D01*
G01X709665Y144098D01*
X709714Y144186D01*
G37*
G36*
G01X744714D02*
Y144630D01*
X744665Y144718D01*
X744621Y144746D01*
G02X742048Y149408I2937J4662D01*
G02X747559Y154918I5511J-1D01*
G02X752221Y152346I0J-5511D01*
G01X752249Y152302D01*
X752337Y152253D01*
X752781D01*
X752869Y152302D01*
X752897Y152346D01*
G02X757559Y154918I4662J-2939D01*
G02X763070Y149408I1J-5510D01*
G02X760497Y144746I-5510J0D01*
G01X760453Y144718D01*
X760404Y144630D01*
Y144186D01*
X760453Y144098D01*
X760497Y144070D01*
G02Y134746I-2937J-4662D01*
G01X760453Y134718D01*
X760404Y134630D01*
Y134186D01*
X760453Y134098D01*
X760497Y134070D01*
G02Y124746I-2937J-4662D01*
G01X760453Y124718D01*
X760404Y124630D01*
Y124186D01*
X760453Y124098D01*
X760497Y124070D01*
G02X763070Y119408I-2937J-4662D01*
G02X757559Y113898I-5511J1D01*
G02X752897Y116470I0J5511D01*
G01X752869Y116514D01*
X752781Y116563D01*
X752337D01*
X752249Y116514D01*
X752221Y116470D01*
G02X747559Y113898I-4662J2939D01*
G02X742048Y119408I-1J5510D01*
G02X744621Y124070I5510J0D01*
G01X744665Y124098D01*
X744714Y124186D01*
Y124630D01*
X744665Y124718D01*
X744621Y124746D01*
G02Y134070I2937J4662D01*
G01X744665Y134098D01*
X744714Y134186D01*
Y134630D01*
X744665Y134718D01*
X744621Y134746D01*
G02Y144070I2937J4662D01*
G01X744665Y144098D01*
X744714Y144186D01*
G37*
G36*
G01X779714D02*
Y144630D01*
X779665Y144718D01*
X779621Y144746D01*
G02X777048Y149408I2937J4662D01*
G02X782559Y154918I5511J-1D01*
G02X787221Y152346I0J-5511D01*
G01X787249Y152302D01*
X787337Y152253D01*
X787781D01*
X787869Y152302D01*
X787897Y152346D01*
G02X792559Y154918I4662J-2939D01*
G02X798070Y149408I1J-5510D01*
G02X795497Y144746I-5510J0D01*
G01X795453Y144718D01*
X795404Y144630D01*
Y144186D01*
X795453Y144098D01*
X795497Y144070D01*
G02Y134746I-2937J-4662D01*
G01X795453Y134718D01*
X795404Y134630D01*
Y134186D01*
X795453Y134098D01*
X795497Y134070D01*
G02Y124746I-2937J-4662D01*
G01X795453Y124718D01*
X795404Y124630D01*
Y124186D01*
X795453Y124098D01*
X795497Y124070D01*
G02X798070Y119408I-2937J-4662D01*
G02X792559Y113898I-5511J1D01*
G02X787897Y116470I0J5511D01*
G01X787869Y116514D01*
X787781Y116563D01*
X787337D01*
X787249Y116514D01*
X787221Y116470D01*
G02X782559Y113898I-4662J2939D01*
G02X777048Y119408I-1J5510D01*
G02X779621Y124070I5510J0D01*
G01X779665Y124098D01*
X779714Y124186D01*
Y124630D01*
X779665Y124718D01*
X779621Y124746D01*
G02Y134070I2937J4662D01*
G01X779665Y134098D01*
X779714Y134186D01*
Y134630D01*
X779665Y134718D01*
X779621Y134746D01*
G02Y144070I2937J4662D01*
G01X779665Y144098D01*
X779714Y144186D01*
G37*
G36*
G01X1138250Y164134D02*
G02X1140000Y164602I1749J-3034D01*
G02Y157598I0J-3502D01*
G02X1138250Y158066I-1J3502D01*
G03X1138050I-100J-173D01*
G02X1136300Y157598I-1749J3034D01*
G02Y164602I0J3502D01*
G02X1138050Y164134I1J-3502D01*
G03X1138250I100J173D01*
G37*
G36*
G01X398907Y154463D02*
Y154907D01*
X398858Y154995D01*
X398814Y155023D01*
G02X396242Y159685I2939J4662D01*
G02X401752Y165196I5510J1D01*
G02X406414Y162623I0J-5510D01*
G01X406442Y162579D01*
X406530Y162530D01*
X406974D01*
X407062Y162579D01*
X407090Y162623D01*
G02X411752Y165196I4662J-2937D01*
G02X417262Y159685I-1J-5511D01*
G02X414690Y155023I-5511J0D01*
G01X414646Y154995D01*
X414597Y154907D01*
Y154463D01*
X414646Y154375D01*
X414690Y154347D01*
G02Y145023I-2939J-4662D01*
G01X414646Y144995D01*
X414597Y144907D01*
Y144463D01*
X414646Y144375D01*
X414690Y144347D01*
G02Y135023I-2939J-4662D01*
G01X414646Y134995D01*
X414597Y134907D01*
Y134463D01*
X414646Y134375D01*
X414690Y134347D01*
G02X417262Y129685I-2939J-4662D01*
G02X411752Y124174I-5510J-1D01*
G02X407090Y126747I0J5510D01*
G01X407062Y126791D01*
X406974Y126840D01*
X406530D01*
X406442Y126791D01*
X406414Y126747D01*
G02X401752Y124174I-4662J2937D01*
G02X396242Y129685I1J5511D01*
G02X398814Y134347I5511J0D01*
G01X398858Y134375D01*
X398907Y134463D01*
Y134907D01*
X398858Y134995D01*
X398814Y135023D01*
G02Y144347I2939J4662D01*
G01X398858Y144375D01*
X398907Y144463D01*
Y144907D01*
X398858Y144995D01*
X398814Y145023D01*
G02Y154347I2939J4662D01*
G01X398858Y154375D01*
X398907Y154463D01*
G37*
G36*
G01X433907D02*
Y154907D01*
X433858Y154995D01*
X433814Y155023D01*
G02X431242Y159685I2939J4662D01*
G02X436752Y165196I5510J1D01*
G02X441414Y162623I0J-5510D01*
G01X441442Y162579D01*
X441530Y162530D01*
X441974D01*
X442062Y162579D01*
X442090Y162623D01*
G02X446752Y165196I4662J-2937D01*
G02X452262Y159685I-1J-5511D01*
G02X449690Y155023I-5511J0D01*
G01X449646Y154995D01*
X449597Y154907D01*
Y154463D01*
X449646Y154375D01*
X449690Y154347D01*
G02Y145023I-2939J-4662D01*
G01X449646Y144995D01*
X449597Y144907D01*
Y144463D01*
X449646Y144375D01*
X449690Y144347D01*
G02Y135023I-2939J-4662D01*
G01X449646Y134995D01*
X449597Y134907D01*
Y134463D01*
X449646Y134375D01*
X449690Y134347D01*
G02X452262Y129685I-2939J-4662D01*
G02X446752Y124174I-5510J-1D01*
G02X442090Y126747I0J5510D01*
G01X442062Y126791D01*
X441974Y126840D01*
X441530D01*
X441442Y126791D01*
X441414Y126747D01*
G02X436752Y124174I-4662J2937D01*
G02X431242Y129685I1J5511D01*
G02X433814Y134347I5511J0D01*
G01X433858Y134375D01*
X433907Y134463D01*
Y134907D01*
X433858Y134995D01*
X433814Y135023D01*
G02Y144347I2939J4662D01*
G01X433858Y144375D01*
X433907Y144463D01*
Y144907D01*
X433858Y144995D01*
X433814Y145023D01*
G02Y154347I2939J4662D01*
G01X433858Y154375D01*
X433907Y154463D01*
G37*
G36*
G01X468907D02*
Y154907D01*
X468858Y154995D01*
X468814Y155023D01*
G02X466242Y159685I2939J4662D01*
G02X471752Y165196I5510J1D01*
G02X476414Y162623I0J-5510D01*
G01X476442Y162579D01*
X476530Y162530D01*
X476974D01*
X477062Y162579D01*
X477090Y162623D01*
G02X481752Y165196I4662J-2937D01*
G02X487262Y159685I-1J-5511D01*
G02X484690Y155023I-5511J0D01*
G01X484646Y154995D01*
X484597Y154907D01*
Y154463D01*
X484646Y154375D01*
X484690Y154347D01*
G02Y145023I-2939J-4662D01*
G01X484646Y144995D01*
X484597Y144907D01*
Y144463D01*
X484646Y144375D01*
X484690Y144347D01*
G02Y135023I-2939J-4662D01*
G01X484646Y134995D01*
X484597Y134907D01*
Y134463D01*
X484646Y134375D01*
X484690Y134347D01*
G02X487262Y129685I-2939J-4662D01*
G02X481752Y124174I-5510J-1D01*
G02X477090Y126747I0J5510D01*
G01X477062Y126791D01*
X476974Y126840D01*
X476530D01*
X476442Y126791D01*
X476414Y126747D01*
G02X471752Y124174I-4662J2937D01*
G02X466242Y129685I1J5511D01*
G02X468814Y134347I5511J0D01*
G01X468858Y134375D01*
X468907Y134463D01*
Y134907D01*
X468858Y134995D01*
X468814Y135023D01*
G02Y144347I2939J4662D01*
G01X468858Y144375D01*
X468907Y144463D01*
Y144907D01*
X468858Y144995D01*
X468814Y145023D01*
G02Y154347I2939J4662D01*
G01X468858Y154375D01*
X468907Y154463D01*
G37*
G36*
G01X1181839Y169249D02*
G02X1183021Y169454I1181J-3297D01*
G02X1184203Y169249I1J-3502D01*
G03X1184339I68J188D01*
G02X1185521Y169454I1181J-3297D01*
G02X1186928Y169160I2J-3502D01*
G03X1187094Y169162I81J183D01*
G02X1188600Y169502I1505J-3162D01*
G02X1192102Y166000I0J-3502D01*
G02X1191763Y164496I-3502J-1D01*
G03X1191764Y164322I181J-86D01*
G02X1192120Y162782I-3146J-1538D01*
G02X1188618Y159280I-3502J0D01*
G02X1186979Y159687I0J3502D01*
G03X1186812Y159696I-93J-177D01*
G02X1185521Y159450I-1289J3256D01*
G02X1184339Y159655I-1J3502D01*
G03X1184203I-68J-188D01*
G02X1183021Y159450I-1181J3297D01*
G02X1181839Y159655I-1J3502D01*
G03X1181703I-68J-188D01*
G02X1180521Y159450I-1181J3297D01*
G02X1179102Y159750I-1J3502D01*
G03X1178940I-81J-183D01*
G02X1177521Y159450I-1418J3202D01*
G02X1174018Y162952I-1J3502D01*
G02X1174319Y164371I3503J-2D01*
G03Y164533I-183J81D01*
G02X1174018Y165952I3202J1421D01*
G02X1177521Y169454I3503J-1D01*
G02X1178940Y169154I1J-3502D01*
G03X1179102I81J183D01*
G02X1180521Y169454I1418J-3202D01*
G02X1181703Y169249I1J-3502D01*
G03X1181839I68J188D01*
G37*
G36*
G01X1018570Y169974D02*
X1018623Y170080D01*
G03X1018636Y170225I-179J89D01*
G02X1018498Y171200I3364J973D01*
G02X1025502I3502J0D01*
G02X1023239Y167924I-3503J0D01*
G03X1023130Y167826I70J-187D01*
G01X1023077Y167720D01*
G03X1023064Y167575I179J-89D01*
G02X1023202Y166600I-3364J-973D01*
G02X1023053Y165589I-3502J0D01*
G01X1023042Y165551D01*
X1023049Y165475D01*
X1023211Y165158D01*
X1023269Y165108D01*
X1023306Y165095D01*
G02X1025670Y161783I-1138J-3312D01*
G02X1024458Y159133I-3503J0D01*
G01X1024424Y159104D01*
X1024389Y159026D01*
Y158634D01*
X1024424Y158556D01*
X1024458Y158527D01*
G02X1025670Y155877I-2291J-2650D01*
G02X1022168Y152374I-3502J-1D01*
G02X1021810Y152393I6J3503D01*
G01X1021764Y152398D01*
X1021678Y152366D01*
X1021395Y152070D01*
X1021367Y151983D01*
X1021374Y151936D01*
G02X1021412Y151424I-3465J-515D01*
G02X1014406I-3503J0D01*
G02X1014645Y152693I3503J-3D01*
G03X1014641Y152848I-187J73D01*
G02X1014334Y154280I3196J1434D01*
G02X1015483Y156874I3503J0D01*
G03X1015548Y157037I-134J148D01*
G02X1015538Y157310I3492J265D01*
G02X1015837Y158728I3502J2D01*
G03Y158891I-183J82D01*
G02X1015528Y160330I3193J1438D01*
G02X1017278Y163363I3503J0D01*
G01X1017320Y163387D01*
X1017372Y163467D01*
X1017417Y163885D01*
X1017383Y163973D01*
X1017347Y164006D01*
G02X1016198Y166600I2354J2594D01*
G02X1018461Y169876I3503J0D01*
G03X1018570Y169974I-70J187D01*
G37*
G36*
G01X1138250Y175334D02*
G02X1140000Y175802I1749J-3034D01*
G02Y168798I0J-3502D01*
G02X1138250Y169266I-1J3502D01*
G03X1138050I-100J-173D01*
G02X1136300Y168798I-1749J3034D01*
G02Y175802I0J3502D01*
G02X1138050Y175334I1J-3502D01*
G03X1138250I100J173D01*
G37*
G36*
G01X1141998Y186729D02*
G02X1143490Y187062I1491J-3169D01*
G02Y180058I0J-3502D01*
G02X1141998Y180391I-1J3502D01*
G03X1141828I-85J-181D01*
G02X1140336Y180058I-1491J3169D01*
G02Y187062I0J3502D01*
G02X1141828Y186729I1J-3502D01*
G03X1141998I85J181D01*
G37*
G36*
G01X1019816Y188686D02*
G02X1020116Y187267I-3202J-1418D01*
G02X1013112I-3502J0D01*
G02X1013412Y188686I3502J1D01*
G03Y188848I-183J81D01*
G02X1013112Y190267I3202J1418D01*
G02X1020116I3502J0D01*
G02X1019816Y188848I-3502J-1D01*
G03Y188686I183J-81D01*
G37*
G36*
G01X1164671Y187837D02*
Y198772D01*
G02X1165171Y199272I500J0D01*
G01X1169952D01*
G02X1170452Y198772I0J-500D01*
G01Y187837D01*
G02X1170253Y187438I-500J0D01*
G01X1170219Y187412D01*
X1170178Y187339D01*
X1170142Y186961D01*
X1170169Y186881D01*
X1170197Y186850D01*
G02X1171102Y184500I-2597J-2349D01*
G02X1170548Y182608I-3502J-2D01*
G03Y182392I168J-108D01*
G02X1171102Y180500I-2948J-1890D01*
G02X1167600Y176998I-3502J0D01*
G02X1166632Y177134I-2J3502D01*
G01X1166581Y177148D01*
X1166480Y177124D01*
X1166151Y176820D01*
X1166119Y176720D01*
X1166130Y176668D01*
G02X1166202Y175959I-3430J-707D01*
G02X1162700Y172456I-3502J-1D01*
G02X1161487Y172673I1J3503D01*
G03X1161352Y172674I-69J-188D01*
G02X1160200Y172480I-1149J3308D01*
G02X1156715Y175628I0J3503D01*
G03X1156597Y175791I-199J-20D01*
G02X1154498Y179000I1403J3209D01*
G02X1158000Y182502I3502J0D01*
G02X1161435Y179684I0J-3503D01*
G01X1161443Y179645D01*
X1161488Y179578D01*
X1161797Y179378D01*
X1161877Y179364D01*
X1161917Y179373D01*
G02X1162700Y179462I785J-3414D01*
G02X1163668Y179325I-2J-3503D01*
G01X1163719Y179311D01*
X1163820Y179335D01*
X1164149Y179639D01*
X1164181Y179739D01*
X1164170Y179791D01*
G02X1164098Y180500I3430J707D01*
G02X1164652Y182392I3502J2D01*
G03Y182608I-168J108D01*
G02X1164098Y184500I2948J1890D01*
G02X1164976Y186820I3502J1D01*
G01X1165005Y186853D01*
X1165030Y186935D01*
X1164979Y187322D01*
X1164933Y187395D01*
X1164896Y187419D01*
G02X1164671Y187837I276J418D01*
G37*
G36*
G01X1127490Y192288D02*
G02X1125918Y191916I-1571J3130D01*
G02Y198920I0J3502D01*
G02X1127325Y198625I0J-3503D01*
G03X1127496Y198630I80J183D01*
G02X1129068Y199002I1571J-3130D01*
G02X1129467Y198980I7J-3502D01*
G03X1129680Y199115I23J199D01*
G02X1133000Y201502I3320J-1115D01*
G02Y194498I0J-3502D01*
G02X1132601Y194520I-7J3502D01*
G03X1132388Y194385I-23J-199D01*
G02X1129068Y191998I-3320J1115D01*
G02X1127661Y192293I0J3503D01*
G03X1127490Y192288I-80J-183D01*
G37*
G36*
G01X1090702Y199419D02*
G02X1091002Y198000I-3202J-1418D01*
G02X1083998I-3502J0D01*
G02X1084298Y199419I3502J1D01*
G03Y199581I-183J81D01*
G02X1083998Y201000I3202J1418D01*
G02X1091002I3502J0D01*
G02X1090702Y199581I-3502J-1D01*
G03Y199419I183J-81D01*
G37*
G36*
G01X587867Y200690D02*
G02X586998Y203000I2633J2309D01*
G02X587203Y204182I3502J1D01*
G03Y204318I-188J68D01*
G02X586998Y205500I3297J1181D01*
G02X594002I3502J0D01*
G02X593797Y204318I-3502J-1D01*
G03Y204182I188J-68D01*
G02X594002Y203000I-3297J-1181D01*
G02X593133Y200690I-3502J-1D01*
G03X593083Y200559I150J-132D01*
G01Y200441D01*
G03X593133Y200310I200J1D01*
G02X594002Y198000I-2633J-2309D01*
G02X593797Y196818I-3502J-1D01*
G03Y196682I188J-68D01*
G02X594002Y195500I-3297J-1181D01*
G02X586998I-3502J0D01*
G02X587203Y196682I3502J1D01*
G03Y196818I-188J68D01*
G02X586998Y198000I3297J1181D01*
G02X587867Y200310I3502J1D01*
G03X587917Y200441I-150J132D01*
G01Y200559D01*
G03X587867Y200690I-200J-1D01*
G37*
G36*
G01X609367D02*
G02X608498Y203000I2633J2309D01*
G02X608703Y204182I3502J1D01*
G03Y204318I-188J68D01*
G02X608498Y205500I3297J1181D01*
G02X615502I3502J0D01*
G02X615297Y204318I-3502J-1D01*
G03Y204182I188J-68D01*
G02X615502Y203000I-3297J-1181D01*
G02X614633Y200690I-3502J-1D01*
G03X614583Y200559I150J-132D01*
G01Y200441D01*
G03X614633Y200310I200J1D01*
G02X615502Y198000I-2633J-2309D01*
G02X615297Y196818I-3502J-1D01*
G03Y196682I188J-68D01*
G02X615502Y195500I-3297J-1181D01*
G02X608498I-3502J0D01*
G02X608703Y196682I3502J1D01*
G03Y196818I-188J68D01*
G02X608498Y198000I3297J1181D01*
G02X609367Y200310I3502J1D01*
G03X609417Y200441I-150J132D01*
G01Y200559D01*
G03X609367Y200690I-200J-1D01*
G37*
G36*
G01X630867D02*
G02X629998Y203000I2633J2309D01*
G02X630203Y204182I3502J1D01*
G03Y204318I-188J68D01*
G02X629998Y205500I3297J1181D01*
G02X637002I3502J0D01*
G02X636797Y204318I-3502J-1D01*
G03Y204182I188J-68D01*
G02X637002Y203000I-3297J-1181D01*
G02X636133Y200690I-3502J-1D01*
G03X636083Y200559I150J-132D01*
G01Y200441D01*
G03X636133Y200310I200J1D01*
G02X637002Y198000I-2633J-2309D01*
G02X636797Y196818I-3502J-1D01*
G03Y196682I188J-68D01*
G02X637002Y195500I-3297J-1181D01*
G02X629998I-3502J0D01*
G02X630203Y196682I3502J1D01*
G03Y196818I-188J68D01*
G02X629998Y198000I3297J1181D01*
G02X630867Y200310I3502J1D01*
G03X630917Y200441I-150J132D01*
G01Y200559D01*
G03X630867Y200690I-200J-1D01*
G37*
G36*
G01X652367D02*
G02X651498Y203000I2633J2309D01*
G02X651703Y204182I3502J1D01*
G03Y204318I-188J68D01*
G02X651498Y205500I3297J1181D01*
G02X658502I3502J0D01*
G02X658297Y204318I-3502J-1D01*
G03Y204182I188J-68D01*
G02X658502Y203000I-3297J-1181D01*
G02X657633Y200690I-3502J-1D01*
G03X657583Y200559I150J-132D01*
G01Y200441D01*
G03X657633Y200310I200J1D01*
G02X658502Y198000I-2633J-2309D01*
G02X658297Y196818I-3502J-1D01*
G03Y196682I188J-68D01*
G02X658502Y195500I-3297J-1181D01*
G02X651498I-3502J0D01*
G02X651703Y196682I3502J1D01*
G03Y196818I-188J68D01*
G02X651498Y198000I3297J1181D01*
G02X652367Y200310I3502J1D01*
G03X652417Y200441I-150J132D01*
G01Y200559D01*
G03X652367Y200690I-200J-1D01*
G37*
G36*
G01X673867D02*
G02X672998Y203000I2633J2309D01*
G02X673203Y204182I3502J1D01*
G03Y204318I-188J68D01*
G02X672998Y205500I3297J1181D01*
G02X680002I3502J0D01*
G02X679797Y204318I-3502J-1D01*
G03Y204182I188J-68D01*
G02X680002Y203000I-3297J-1181D01*
G02X679133Y200690I-3502J-1D01*
G03X679083Y200559I150J-132D01*
G01Y200441D01*
G03X679133Y200310I200J1D01*
G02X680002Y198000I-2633J-2309D01*
G02X679797Y196818I-3502J-1D01*
G03Y196682I188J-68D01*
G02X680002Y195500I-3297J-1181D01*
G02X672998I-3502J0D01*
G02X673203Y196682I3502J1D01*
G03Y196818I-188J68D01*
G02X672998Y198000I3297J1181D01*
G02X673867Y200310I3502J1D01*
G03X673917Y200441I-150J132D01*
G01Y200559D01*
G03X673867Y200690I-200J-1D01*
G37*
G36*
G01X695357D02*
G02X694488Y203000I2633J2309D01*
G02X694693Y204182I3502J1D01*
G03Y204318I-188J68D01*
G02X694488Y205500I3297J1181D01*
G02X701492I3502J0D01*
G02X701287Y204318I-3502J-1D01*
G03Y204182I188J-68D01*
G02X701492Y203000I-3297J-1181D01*
G02X700623Y200690I-3502J-1D01*
G03X700573Y200559I150J-132D01*
G01Y200441D01*
G03X700623Y200310I200J1D01*
G02X701492Y198000I-2633J-2309D01*
G02X701287Y196818I-3502J-1D01*
G03Y196682I188J-68D01*
G02X701492Y195500I-3297J-1181D01*
G02X694488I-3502J0D01*
G02X694693Y196682I3502J1D01*
G03Y196818I-188J68D01*
G02X694488Y198000I3297J1181D01*
G02X695357Y200310I3502J1D01*
G03X695407Y200441I-150J132D01*
G01Y200559D01*
G03X695357Y200690I-200J-1D01*
G37*
G36*
G01X716857D02*
G02X715988Y203000I2633J2309D01*
G02X716193Y204182I3502J1D01*
G03Y204318I-188J68D01*
G02X715988Y205500I3297J1181D01*
G02X722992I3502J0D01*
G02X722787Y204318I-3502J-1D01*
G03Y204182I188J-68D01*
G02X722992Y203000I-3297J-1181D01*
G02X722123Y200690I-3502J-1D01*
G03X722073Y200559I150J-132D01*
G01Y200441D01*
G03X722123Y200310I200J1D01*
G02X722992Y198000I-2633J-2309D01*
G02X722787Y196818I-3502J-1D01*
G03Y196682I188J-68D01*
G02X722992Y195500I-3297J-1181D01*
G02X715988I-3502J0D01*
G02X716193Y196682I3502J1D01*
G03Y196818I-188J68D01*
G02X715988Y198000I3297J1181D01*
G02X716857Y200310I3502J1D01*
G03X716907Y200441I-150J132D01*
G01Y200559D01*
G03X716857Y200690I-200J-1D01*
G37*
G36*
G01X173348Y199403D02*
G02X171158Y202650I1312J3247D01*
G02X171501Y204164I3503J2D01*
G03Y204336I-180J86D01*
G02X171158Y205850I3160J1512D01*
G02X178162I3502J0D01*
G02X177819Y204336I-3503J-2D01*
G03Y204164I180J-86D01*
G02X178162Y202650I-3160J-1512D01*
G02X177677Y200871I-3502J-1D01*
G01X177655Y200834D01*
X177646Y200747D01*
X177772Y200377D01*
X177832Y200314D01*
X177872Y200297D01*
G02X177932Y200273I-1271J-3264D01*
G03X178088I78J184D01*
G02X179460Y200552I1370J-3223D01*
G02X180784Y200292I0J-3501D01*
G03X180936I76J186D01*
G02X182260Y200552I1324J-3241D01*
G02Y193548I0J-3502D01*
G02X180936Y193808I0J3501D01*
G03X180784I-76J-186D01*
G02X179460Y193548I-1324J3241D01*
G02X178088Y193827I-2J3502D01*
G03X177932I-78J-184D01*
G02X176560Y193548I-1370J3223D01*
G02X173058Y197050I0J3502D01*
G02X173543Y198829I3502J1D01*
G01X173565Y198866D01*
X173574Y198953D01*
X173448Y199323D01*
X173388Y199386D01*
X173348Y199403D01*
G37*
G36*
G01X280367Y201190D02*
G02X279498Y203500I2633J2309D01*
G02X279703Y204682I3502J1D01*
G03Y204818I-188J68D01*
G02X279498Y206000I3297J1181D01*
G02X286502I3502J0D01*
G02X286297Y204818I-3502J-1D01*
G03Y204682I188J-68D01*
G02X286502Y203500I-3297J-1181D01*
G02X285633Y201190I-3502J-1D01*
G03X285583Y201059I150J-132D01*
G01Y200941D01*
G03X285633Y200810I200J1D01*
G02X286502Y198500I-2633J-2309D01*
G02X286297Y197318I-3502J-1D01*
G03Y197182I188J-68D01*
G02X286502Y196000I-3297J-1181D01*
G02X279498I-3502J0D01*
G02X279703Y197182I3502J1D01*
G03Y197318I-188J68D01*
G02X279498Y198500I3297J1181D01*
G02X280367Y200810I3502J1D01*
G03X280417Y200941I-150J132D01*
G01Y201059D01*
G03X280367Y201190I-200J-1D01*
G37*
G36*
G01X301867D02*
G02X300998Y203500I2633J2309D01*
G02X301203Y204682I3502J1D01*
G03Y204818I-188J68D01*
G02X300998Y206000I3297J1181D01*
G02X308002I3502J0D01*
G02X307797Y204818I-3502J-1D01*
G03Y204682I188J-68D01*
G02X308002Y203500I-3297J-1181D01*
G02X307133Y201190I-3502J-1D01*
G03X307083Y201059I150J-132D01*
G01Y200941D01*
G03X307133Y200810I200J1D01*
G02X308002Y198500I-2633J-2309D01*
G02X307797Y197318I-3502J-1D01*
G03Y197182I188J-68D01*
G02X308002Y196000I-3297J-1181D01*
G02X300998I-3502J0D01*
G02X301203Y197182I3502J1D01*
G03Y197318I-188J68D01*
G02X300998Y198500I3297J1181D01*
G02X301867Y200810I3502J1D01*
G03X301917Y200941I-150J132D01*
G01Y201059D01*
G03X301867Y201190I-200J-1D01*
G37*
G36*
G01X323367D02*
G02X322498Y203500I2633J2309D01*
G02X322703Y204682I3502J1D01*
G03Y204818I-188J68D01*
G02X322498Y206000I3297J1181D01*
G02X329502I3502J0D01*
G02X329297Y204818I-3502J-1D01*
G03Y204682I188J-68D01*
G02X329502Y203500I-3297J-1181D01*
G02X328633Y201190I-3502J-1D01*
G03X328583Y201059I150J-132D01*
G01Y200941D01*
G03X328633Y200810I200J1D01*
G02X329502Y198500I-2633J-2309D01*
G02X329297Y197318I-3502J-1D01*
G03Y197182I188J-68D01*
G02X329502Y196000I-3297J-1181D01*
G02X322498I-3502J0D01*
G02X322703Y197182I3502J1D01*
G03Y197318I-188J68D01*
G02X322498Y198500I3297J1181D01*
G02X323367Y200810I3502J1D01*
G03X323417Y200941I-150J132D01*
G01Y201059D01*
G03X323367Y201190I-200J-1D01*
G37*
G36*
G01X344867D02*
G02X343998Y203500I2633J2309D01*
G02X344203Y204682I3502J1D01*
G03Y204818I-188J68D01*
G02X343998Y206000I3297J1181D01*
G02X351002I3502J0D01*
G02X350797Y204818I-3502J-1D01*
G03Y204682I188J-68D01*
G02X351002Y203500I-3297J-1181D01*
G02X350133Y201190I-3502J-1D01*
G03X350083Y201059I150J-132D01*
G01Y200941D01*
G03X350133Y200810I200J1D01*
G02X351002Y198500I-2633J-2309D01*
G02X350797Y197318I-3502J-1D01*
G03Y197182I188J-68D01*
G02X351002Y196000I-3297J-1181D01*
G02X343998I-3502J0D01*
G02X344203Y197182I3502J1D01*
G03Y197318I-188J68D01*
G02X343998Y198500I3297J1181D01*
G02X344867Y200810I3502J1D01*
G03X344917Y200941I-150J132D01*
G01Y201059D01*
G03X344867Y201190I-200J-1D01*
G37*
G36*
G01X366367D02*
G02X365498Y203500I2633J2309D01*
G02X365703Y204682I3502J1D01*
G03Y204818I-188J68D01*
G02X365498Y206000I3297J1181D01*
G02X372502I3502J0D01*
G02X372297Y204818I-3502J-1D01*
G03Y204682I188J-68D01*
G02X372502Y203500I-3297J-1181D01*
G02X371633Y201190I-3502J-1D01*
G03X371583Y201059I150J-132D01*
G01Y200941D01*
G03X371633Y200810I200J1D01*
G02X372502Y198500I-2633J-2309D01*
G02X372297Y197318I-3502J-1D01*
G03Y197182I188J-68D01*
G02X372502Y196000I-3297J-1181D01*
G02X365498I-3502J0D01*
G02X365703Y197182I3502J1D01*
G03Y197318I-188J68D01*
G02X365498Y198500I3297J1181D01*
G02X366367Y200810I3502J1D01*
G03X366417Y200941I-150J132D01*
G01Y201059D01*
G03X366367Y201190I-200J-1D01*
G37*
G36*
G01X387867D02*
G02X386998Y203500I2633J2309D01*
G02X387203Y204682I3502J1D01*
G03Y204818I-188J68D01*
G02X386998Y206000I3297J1181D01*
G02X394002I3502J0D01*
G02X393797Y204818I-3502J-1D01*
G03Y204682I188J-68D01*
G02X394002Y203500I-3297J-1181D01*
G02X393133Y201190I-3502J-1D01*
G03X393083Y201059I150J-132D01*
G01Y200941D01*
G03X393133Y200810I200J1D01*
G02X394002Y198500I-2633J-2309D01*
G02X393797Y197318I-3502J-1D01*
G03Y197182I188J-68D01*
G02X394002Y196000I-3297J-1181D01*
G02X386998I-3502J0D01*
G02X387203Y197182I3502J1D01*
G03Y197318I-188J68D01*
G02X386998Y198500I3297J1181D01*
G02X387867Y200810I3502J1D01*
G03X387917Y200941I-150J132D01*
G01Y201059D01*
G03X387867Y201190I-200J-1D01*
G37*
G36*
G01X409367D02*
G02X408498Y203500I2633J2309D01*
G02X408703Y204682I3502J1D01*
G03Y204818I-188J68D01*
G02X408498Y206000I3297J1181D01*
G02X415502I3502J0D01*
G02X415297Y204818I-3502J-1D01*
G03Y204682I188J-68D01*
G02X415502Y203500I-3297J-1181D01*
G02X414633Y201190I-3502J-1D01*
G03X414583Y201059I150J-132D01*
G01Y200941D01*
G03X414633Y200810I200J1D01*
G02X415502Y198500I-2633J-2309D01*
G02X415297Y197318I-3502J-1D01*
G03Y197182I188J-68D01*
G02X415502Y196000I-3297J-1181D01*
G02X408498I-3502J0D01*
G02X408703Y197182I3502J1D01*
G03Y197318I-188J68D01*
G02X408498Y198500I3297J1181D01*
G02X409367Y200810I3502J1D01*
G03X409417Y200941I-150J132D01*
G01Y201059D01*
G03X409367Y201190I-200J-1D01*
G37*
G36*
G01X190958Y206781D02*
G02X190658Y208200I3202J1418D01*
G02X194160Y211702I3502J0D01*
G02X195579Y211402I1J-3502D01*
G03X195741I81J183D01*
G02X197160Y211702I1418J-3202D01*
G02X198579Y211402I1J-3502D01*
G03X198741I81J183D01*
G02X200160Y211702I1418J-3202D01*
G02X203662Y208200I0J-3502D01*
G02X203362Y206781I-3502J-1D01*
G03Y206619I183J-81D01*
G02X203662Y205200I-3202J-1418D01*
G02X200160Y201698I-3502J0D01*
G02X198741Y201998I-1J3502D01*
G03X198579I-81J-183D01*
G02X197160Y201698I-1418J3202D01*
G02X195741Y201998I-1J3502D01*
G03X195579I-81J-183D01*
G02X194160Y201698I-1418J3202D01*
G02X190658Y205200I0J3502D01*
G02X190958Y206619I3502J1D01*
G03Y206781I-183J81D01*
G37*
G36*
G01X188462Y206769D02*
G02X188762Y205350I-3202J-1418D01*
G02X181758I-3502J0D01*
G02X182058Y206769I3502J1D01*
G03Y206931I-183J81D01*
G02X181758Y208350I3202J1418D01*
G02X188762I3502J0D01*
G02X188462Y206931I-3502J-1D01*
G03Y206769I183J-81D01*
G37*
G36*
G01X1168298Y209581D02*
G02X1167998Y211000I3202J1418D01*
G02X1168298Y212419I3502J1D01*
G03Y212581I-183J81D01*
G02X1167998Y214000I3202J1418D01*
G02X1171500Y217502I3502J0D01*
G02X1172919Y217202I1J-3502D01*
G03X1173081I81J183D01*
G02X1174500Y217502I1418J-3202D01*
G02X1178002Y214000I0J-3502D01*
G02X1177702Y212581I-3502J-1D01*
G03Y212419I183J-81D01*
G02X1178002Y211000I-3202J-1418D01*
G02X1177702Y209581I-3502J-1D01*
G03Y209419I183J-81D01*
G02X1178002Y208000I-3202J-1418D01*
G02X1177702Y206581I-3502J-1D01*
G03Y206419I183J-81D01*
G02X1178002Y205000I-3202J-1418D01*
G02X1174500Y201498I-3502J0D01*
G02X1173081Y201798I-1J3502D01*
G03X1172919I-81J-183D01*
G02X1171500Y201498I-1418J3202D01*
G02X1167998Y205000I0J3502D01*
G02X1168298Y206419I3502J1D01*
G03Y206581I-183J81D01*
G02X1167998Y208000I3202J1418D01*
G02X1168298Y209419I3502J1D01*
G03Y209581I-183J81D01*
G37*
G36*
G01X149247Y224908D02*
G02X148832Y226563I3087J1654D01*
G02X149247Y228218I3502J1D01*
G03Y228408I-176J95D01*
G02X148832Y230063I3087J1654D01*
G02X152065Y233555I3502J0D01*
G03X152211Y233636I-15J200D01*
G02X155034Y235066I2824J-2073D01*
G02X158536Y231563I-1J-3503D01*
G02X158121Y229908I-3502J-1D01*
G03Y229718I176J-95D01*
G02X158536Y228063I-3087J-1654D01*
G02X158121Y226408I-3502J-1D01*
G03Y226218I176J-95D01*
G02X158536Y224563I-3087J-1654D01*
G02X155303Y221071I-3502J0D01*
G03X155157Y220990I15J-200D01*
G02X154140Y220062I-2823J2073D01*
G03X154048Y219846I103J-171D01*
G02X154136Y219063I-3414J-780D01*
G02X147132I-3502J0D01*
G02X148828Y222064I3503J0D01*
G03X148920Y222280I-103J171D01*
G02X148832Y223063I3414J780D01*
G02X149247Y224718I3502J1D01*
G03Y224908I-176J95D01*
G37*
G36*
G01X1064581Y261202D02*
G02X1066000Y261502I1418J-3202D01*
G02X1067419Y261202I1J-3502D01*
G03X1067581I81J183D01*
G02X1069000Y261502I1418J-3202D01*
G02X1070419Y261202I1J-3502D01*
G03X1070581I81J183D01*
G02X1072000Y261502I1418J-3202D01*
G02X1075502Y258000I0J-3502D01*
G02X1075202Y256581I-3502J-1D01*
G03Y256419I183J-81D01*
G02X1075502Y255000I-3202J-1418D01*
G02X1072000Y251498I-3502J0D01*
G02X1070581Y251798I-1J3502D01*
G03X1070419I-81J-183D01*
G02X1069611Y251551I-1420J3202D01*
G03X1069449Y251389I35J-197D01*
G02X1069202Y250581I-3449J612D01*
G03Y250419I183J-81D01*
G02X1069449Y249611I-3202J-1420D01*
G03X1069611Y249449I197J35D01*
G02X1070419Y249202I-612J-3449D01*
G03X1070581I81J183D01*
G02X1072000Y249502I1418J-3202D01*
G02X1075502Y246000I0J-3502D01*
G02X1075202Y244581I-3502J-1D01*
G03Y244419I183J-81D01*
G02X1075502Y243000I-3202J-1418D01*
G02X1072000Y239498I-3502J0D01*
G02X1070581Y239798I-1J3502D01*
G03X1070419I-81J-183D01*
G02X1069000Y239498I-1418J3202D01*
G02X1067581Y239798I-1J3502D01*
G03X1067419I-81J-183D01*
G02X1066000Y239498I-1418J3202D01*
G02X1064581Y239798I-1J3502D01*
G03X1064419I-81J-183D01*
G02X1063000Y239498I-1418J3202D01*
G02X1061581Y239798I-1J3502D01*
G03X1061419I-81J-183D01*
G02X1060000Y239498I-1418J3202D01*
G02X1056498Y243000I0J3502D01*
G02X1056798Y244419I3502J1D01*
G03Y244581I-183J81D01*
G02X1056498Y246000I3202J1418D01*
G02X1056798Y247419I3502J1D01*
G03Y247581I-183J81D01*
G02X1056498Y249000I3202J1418D01*
G02X1056798Y250419I3502J1D01*
G03Y250581I-183J81D01*
G02X1056498Y252000I3202J1418D01*
G02X1056798Y253419I3502J1D01*
G03Y253581I-183J81D01*
G02X1056498Y255000I3202J1418D01*
G02X1056798Y256419I3502J1D01*
G03Y256581I-183J81D01*
G02X1056498Y258000I3202J1418D01*
G02X1060000Y261502I3502J0D01*
G02X1061419Y261202I1J-3502D01*
G03X1061581I81J183D01*
G02X1063000Y261502I1418J-3202D01*
G02X1064419Y261202I1J-3502D01*
G03X1064581I81J183D01*
G37*
G36*
G01X105398Y257141D02*
G02X105098Y258560I3202J1418D01*
G02X105398Y259979I3502J1D01*
G03Y260141I-183J81D01*
G02X105098Y261560I3202J1418D01*
G02X108600Y265062I3502J0D01*
G02X110019Y264762I1J-3502D01*
G03X110181I81J183D01*
G02X111600Y265062I1418J-3202D01*
G02X115102Y261560I0J-3502D01*
G02X114802Y260141I-3502J-1D01*
G03Y259979I183J-81D01*
G02X115102Y258560I-3202J-1418D01*
G02X114802Y257141I-3502J-1D01*
G03Y256979I183J-81D01*
G02X115102Y255560I-3202J-1418D01*
G02X111600Y252058I-3502J0D01*
G02X110181Y252358I-1J3502D01*
G03X110019I-81J-183D01*
G02X108600Y252058I-1418J3202D01*
G02X105098Y255560I0J3502D01*
G02X105398Y256979I3502J1D01*
G03Y257141I-183J81D01*
G37*
G36*
G01X43435Y269857D02*
G02X38780Y267196I-4655J2741D01*
G02X33378Y272598I0J5402D01*
G02X34447Y275825I5402J1D01*
G03Y276064I-160J120D01*
G02X33378Y279291I4333J3226D01*
G02X38780Y284694I5402J1D01*
G02X43435Y282032I-1J-5403D01*
G01X43462Y281986D01*
X43554Y281934D01*
X44006D01*
X44098Y281986D01*
X44125Y282032D01*
G02X48780Y284694I4656J-2741D01*
G02X54182Y279291I-1J-5403D01*
G02X53113Y276064I-5402J-1D01*
G03Y275825I160J-119D01*
G02X54182Y272598I-4333J-3226D01*
G02X48780Y267196I-5402J0D01*
G02X44125Y269857I0J5402D01*
G01X44098Y269903D01*
X44006Y269955D01*
X43554D01*
X43462Y269903D01*
X43435Y269857D01*
G37*
G36*
G01X561243Y272218D02*
X561401Y272604D01*
X561394Y272697D01*
X561369Y272738D01*
G02X560128Y277204I7411J4465D01*
G02X568780Y285856I8652J0D01*
G02X575949Y282049I1J-8652D01*
G01X575977Y282008D01*
X576064Y281961D01*
X576496D01*
X576583Y282008D01*
X576611Y282049D01*
G02X583780Y285856I7168J-4845D01*
G02Y268552I0J-8652D01*
G02X576611Y272359I-1J8652D01*
G01X576583Y272400D01*
X576496Y272447D01*
X576064D01*
X575977Y272400D01*
X575949Y272359D01*
G02X568780Y268552I-7168J4845D01*
G02X567856Y268601I-4J8652D01*
G01X567808Y268606D01*
X567721Y268574D01*
X567437Y268268D01*
X567411Y268178D01*
X567420Y268131D01*
G02X567504Y267204I-5018J-922D01*
G02X557300I-5102J0D01*
G02X561126Y272144I5102J0D01*
G01X561173Y272157D01*
X561243Y272218D01*
G37*
G36*
G01X718724D02*
X718882Y272604D01*
X718875Y272697D01*
X718850Y272738D01*
G02X717608Y277204I7411J4467D01*
G02X726261Y285856I8653J-1D01*
G02X733430Y282049I1J-8652D01*
G01X733458Y282008D01*
X733545Y281961D01*
X733977D01*
X734064Y282008D01*
X734092Y282049D01*
G02X741261Y285856I7168J-4845D01*
G02Y268552I0J-8652D01*
G02X734092Y272359I-1J8652D01*
G01X734064Y272400D01*
X733977Y272447D01*
X733545D01*
X733458Y272400D01*
X733430Y272359D01*
G02X726261Y268552I-7168J4845D01*
G02X725337Y268601I-4J8652D01*
G01X725289Y268606D01*
X725202Y268574D01*
X724918Y268268D01*
X724892Y268178D01*
X724901Y268131D01*
G02X724986Y267204I-5018J-928D01*
G02X714780I-5103J0D01*
G02X718607Y272144I5102J0D01*
G01X718654Y272157D01*
X718724Y272218D01*
G37*
G36*
G01X274082Y284635D02*
G02X277219Y286580I3137J-1557D01*
G02X279111Y286026I2J-3502D01*
G03X279327I108J168D01*
G02X281219Y286580I1890J-2948D01*
G02X283111Y286026I2J-3502D01*
G03X283327I108J168D01*
G02X285219Y286580I1890J-2948D01*
G02X288722Y283078I1J-3502D01*
G02X288167Y281186I-3502J0D01*
G03Y280970I168J-108D01*
G02Y277186I-2947J-1892D01*
G03Y276970I168J-108D01*
G02Y273186I-2947J-1892D01*
G03Y272970I168J-108D01*
G02X288722Y271078I-2947J-1892D01*
G02X285219Y267576I-3503J1D01*
G02X283327Y268130I-2J3502D01*
G03X283111I-108J-168D01*
G02X281219Y267576I-1890J2948D01*
G02X279327Y268130I-2J3502D01*
G03X279111I-108J-168D01*
G02X277219Y267576I-1890J2948D01*
G02X274001Y269696I0J3502D01*
G01X273983Y269736D01*
X273919Y269795D01*
X273544Y269911D01*
X273458Y269900D01*
X273421Y269877D01*
G02X268819Y268552I-4601J7327D01*
G02X261650Y272359I-1J8652D01*
G01X261622Y272400D01*
X261535Y272447D01*
X261103D01*
X261016Y272400D01*
X260988Y272359D01*
G02X253819Y268552I-7168J4845D01*
G02X252895Y268601I-4J8652D01*
G01X252847Y268606D01*
X252760Y268574D01*
X252476Y268268D01*
X252450Y268178D01*
X252459Y268131D01*
G02X252544Y267204I-5018J-928D01*
G02X242338I-5103J0D01*
G02X246165Y272144I5102J0D01*
G01X246212Y272157D01*
X246282Y272218D01*
X246440Y272604D01*
X246433Y272697D01*
X246408Y272738D01*
G02X245166Y277204I7411J4467D01*
G02X253819Y285856I8653J-1D01*
G02X260988Y282049I1J-8652D01*
G01X261016Y282008D01*
X261103Y281961D01*
X261535D01*
X261622Y282008D01*
X261650Y282049D01*
G02X268819Y285856I7168J-4845D01*
G02X273507Y284477I2J-8652D01*
G01X273543Y284453D01*
X273626Y284440D01*
X273998Y284543D01*
X274062Y284596D01*
X274082Y284635D01*
G37*
G36*
G01X431368Y284755D02*
G02X434499Y286688I3131J-1569D01*
G02X436391Y286134I2J-3502D01*
G03X436607I108J168D01*
G02X438499Y286688I1890J-2948D01*
G02X440391Y286134I2J-3502D01*
G03X440607I108J168D01*
G02X442499Y286688I1890J-2948D01*
G02X446002Y283186I1J-3502D01*
G02X445447Y281294I-3502J0D01*
G03Y281078I168J-108D01*
G02Y277294I-2947J-1892D01*
G03Y277078I168J-108D01*
G02Y273294I-2947J-1892D01*
G03Y273078I168J-108D01*
G02X446002Y271186I-2947J-1892D01*
G02X442499Y267684I-3503J1D01*
G02X440607Y268238I-2J3502D01*
G03X440391I-108J-168D01*
G02X438499Y267684I-1890J2948D01*
G02X436607Y268238I-2J3502D01*
G03X436391I-108J-168D01*
G02X434499Y267684I-1890J2948D01*
G02X431355Y269642I0J3503D01*
G01X431337Y269680D01*
X431272Y269734D01*
X430908Y269840D01*
X430825Y269829D01*
X430789Y269807D01*
G02X426299Y268552I-4488J7398D01*
G02X419130Y272359I-1J8652D01*
G01X419102Y272400D01*
X419015Y272447D01*
X418583D01*
X418496Y272400D01*
X418468Y272359D01*
G02X411299Y268552I-7168J4845D01*
G02X410375Y268601I-4J8652D01*
G01X410327Y268606D01*
X410240Y268574D01*
X409956Y268268D01*
X409930Y268178D01*
X409939Y268131D01*
G02X410024Y267204I-5018J-928D01*
G02X399818I-5103J0D01*
G02X403645Y272144I5102J0D01*
G01X403692Y272157D01*
X403762Y272218D01*
X403920Y272604D01*
X403913Y272697D01*
X403888Y272738D01*
G02X402646Y277204I7411J4467D01*
G02X411299Y285856I8653J-1D01*
G02X418468Y282049I1J-8652D01*
G01X418496Y282008D01*
X418583Y281961D01*
X419015D01*
X419102Y282008D01*
X419130Y282049D01*
G02X426299Y285856I7168J-4845D01*
G02X430802Y284593I2J-8652D01*
G01X430838Y284570D01*
X430920Y284559D01*
X431285Y284664D01*
X431348Y284717D01*
X431368Y284755D01*
G37*
G36*
G01X43554Y301934D02*
X44006D01*
X44098Y301986D01*
X44125Y302032D01*
G02X48780Y304694I4656J-2741D01*
G02X54182Y299291I-1J-5403D01*
G02X53113Y296064I-5402J-1D01*
G03Y295825I160J-119D01*
G02X54182Y292598I-4333J-3226D01*
G02X48780Y287196I-5402J0D01*
G02X44125Y289857I0J5402D01*
G01X44098Y289903D01*
X44006Y289955D01*
X43554D01*
X43462Y289903D01*
X43435Y289857D01*
G02X38780Y287196I-4655J2741D01*
G02X33378Y292598I0J5402D01*
G02X34447Y295825I5402J1D01*
G03Y296064I-160J120D01*
G02X33378Y299291I4333J3226D01*
G02X38780Y304694I5402J1D01*
G02X43435Y302032I-1J-5403D01*
G01X43462Y301986D01*
X43554Y301934D01*
G37*
G36*
G01X1064581Y308702D02*
G02X1066000Y309002I1418J-3202D01*
G02X1067419Y308702I1J-3502D01*
G03X1067581I81J183D01*
G02X1069000Y309002I1418J-3202D01*
G02X1070419Y308702I1J-3502D01*
G03X1070581I81J183D01*
G02X1072000Y309002I1418J-3202D01*
G02X1075502Y305500I0J-3502D01*
G02X1075202Y304081I-3502J-1D01*
G03Y303919I183J-81D01*
G02X1075502Y302500I-3202J-1418D01*
G02X1072000Y298998I-3502J0D01*
G02X1070581Y299298I-1J3502D01*
G03X1070419I-81J-183D01*
G02X1069611Y299051I-1420J3202D01*
G03X1069449Y298889I35J-197D01*
G02X1069202Y298081I-3449J612D01*
G03Y297919I183J-81D01*
G02X1069449Y297111I-3202J-1420D01*
G03X1069611Y296949I197J35D01*
G02X1070419Y296702I-612J-3449D01*
G03X1070581I81J183D01*
G02X1072000Y297002I1418J-3202D01*
G02X1075502Y293500I0J-3502D01*
G02X1075202Y292081I-3502J-1D01*
G03Y291919I183J-81D01*
G02X1075502Y290500I-3202J-1418D01*
G02X1072000Y286998I-3502J0D01*
G02X1070581Y287298I-1J3502D01*
G03X1070419I-81J-183D01*
G02X1069000Y286998I-1418J3202D01*
G02X1067581Y287298I-1J3502D01*
G03X1067419I-81J-183D01*
G02X1066000Y286998I-1418J3202D01*
G02X1064581Y287298I-1J3502D01*
G03X1064419I-81J-183D01*
G02X1063000Y286998I-1418J3202D01*
G02X1061581Y287298I-1J3502D01*
G03X1061419I-81J-183D01*
G02X1060000Y286998I-1418J3202D01*
G02X1056498Y290500I0J3502D01*
G02X1056798Y291919I3502J1D01*
G03Y292081I-183J81D01*
G02X1056498Y293500I3202J1418D01*
G02X1056798Y294919I3502J1D01*
G03Y295081I-183J81D01*
G02X1056498Y296500I3202J1418D01*
G02X1056798Y297919I3502J1D01*
G03Y298081I-183J81D01*
G02X1056498Y299500I3202J1418D01*
G02X1056798Y300919I3502J1D01*
G03Y301081I-183J81D01*
G02X1056498Y302500I3202J1418D01*
G02X1056798Y303919I3502J1D01*
G03Y304081I-183J81D01*
G02X1056498Y305500I3202J1418D01*
G02X1060000Y309002I3502J0D01*
G02X1061419Y308702I1J-3502D01*
G03X1061581I81J183D01*
G02X1063000Y309002I1418J-3202D01*
G02X1064419Y308702I1J-3502D01*
G03X1064581I81J183D01*
G37*
G36*
G01X43781Y349915D02*
G02X48780Y354726I4999J-192D01*
G02X53782Y349724I0J-5002D01*
G02X48971Y344725I-5003J0D01*
G03X48779Y344533I8J-200D01*
G02X43780Y339722I-4999J192D01*
G02X38778Y344724I0J5002D01*
G02X43589Y349723I5003J0D01*
G03X43781Y349915I-8J200D01*
G37*
G36*
G01X1059200Y356470D02*
X1059308Y356917D01*
X1059276Y357021D01*
X1059236Y357058D01*
G02X1058098Y359642I2365J2584D01*
G02X1065102I3502J0D01*
G02X1063920Y357018I-3502J-1D01*
G01X1063879Y356982D01*
X1063845Y356880D01*
X1063940Y356433D01*
X1064011Y356354D01*
X1064063Y356337D01*
G02X1064419Y356202I-1062J-3337D01*
G03X1064581I81J183D01*
G02X1066000Y356502I1418J-3202D01*
G02X1067419Y356202I1J-3502D01*
G03X1067581I81J183D01*
G02X1069000Y356502I1418J-3202D01*
G02X1070419Y356202I1J-3502D01*
G03X1070581I81J183D01*
G02X1072000Y356502I1418J-3202D01*
G02X1075502Y353000I0J-3502D01*
G02X1075202Y351581I-3502J-1D01*
G03Y351419I183J-81D01*
G02X1075502Y350000I-3202J-1418D01*
G02X1072000Y346498I-3502J0D01*
G02X1070581Y346798I-1J3502D01*
G03X1070419I-81J-183D01*
G02X1069611Y346551I-1420J3202D01*
G03X1069449Y346389I35J-197D01*
G02X1069202Y345581I-3449J612D01*
G03Y345419I183J-81D01*
G02X1069449Y344611I-3202J-1420D01*
G03X1069611Y344449I197J35D01*
G02X1070419Y344202I-612J-3449D01*
G03X1070581I81J183D01*
G02X1072000Y344502I1418J-3202D01*
G02X1075502Y341000I0J-3502D01*
G02X1075202Y339581I-3502J-1D01*
G03Y339419I183J-81D01*
G02X1075502Y338000I-3202J-1418D01*
G02X1072000Y334498I-3502J0D01*
G02X1070581Y334798I-1J3502D01*
G03X1070419I-81J-183D01*
G02X1069000Y334498I-1418J3202D01*
G02X1067581Y334798I-1J3502D01*
G03X1067419I-81J-183D01*
G02X1066000Y334498I-1418J3202D01*
G02X1064581Y334798I-1J3502D01*
G03X1064419I-81J-183D01*
G02X1063000Y334498I-1418J3202D01*
G02X1061581Y334798I-1J3502D01*
G03X1061419I-81J-183D01*
G02X1060000Y334498I-1418J3202D01*
G02X1056498Y338000I0J3502D01*
G02X1056798Y339419I3502J1D01*
G03Y339581I-183J81D01*
G02X1056498Y341000I3202J1418D01*
G02X1056798Y342419I3502J1D01*
G03Y342581I-183J81D01*
G02X1056498Y344000I3202J1418D01*
G02X1056798Y345419I3502J1D01*
G03Y345581I-183J81D01*
G02X1056498Y347000I3202J1418D01*
G02X1056798Y348419I3502J1D01*
G03Y348581I-183J81D01*
G02X1056498Y350000I3202J1418D01*
G02X1056798Y351419I3502J1D01*
G03Y351581I-183J81D01*
G02X1056498Y353000I3202J1418D01*
G02X1059072Y356377I3502J0D01*
G01X1059125Y356392D01*
X1059200Y356470D01*
G37*
G36*
G01X946985Y388121D02*
X947372D01*
X947450Y388156D01*
X947479Y388189D01*
G02X950110Y389380I2632J-2312D01*
G02X951529Y389079I-2J-3503D01*
G03X951691I81J183D01*
G02X953110Y389380I1421J-3202D01*
G02Y382374I0J-3503D01*
G02X951691Y382675I2J3503D01*
G03X951529I-81J-183D01*
G02X950110Y382374I-1421J3202D01*
G02X947479Y383565I1J3503D01*
G01X947450Y383598D01*
X947372Y383633D01*
X946985D01*
X946907Y383598D01*
X946878Y383565D01*
G02X944247Y382374I-2632J2312D01*
G02X942828Y382675I2J3503D01*
G03X942666I-81J-183D01*
G02X941247Y382374I-1421J3202D01*
G02X938162Y384219I0J3502D01*
G01X938135Y384269D01*
X938039Y384325D01*
X937571Y384318D01*
X937477Y384259D01*
X937452Y384208D01*
G02X934317Y382268I-3135J1563D01*
G02X932898Y382569I2J3503D01*
G03X932736I-81J-183D01*
G02X931317Y382268I-1421J3202D01*
G02X928686Y383459I1J3503D01*
G01X928657Y383492D01*
X928579Y383527D01*
X928192D01*
X928114Y383492D01*
X928085Y383459D01*
G02X925454Y382268I-2632J2312D01*
G02X924035Y382569I2J3503D01*
G03X923873I-81J-183D01*
G02X922454Y382268I-1421J3202D01*
G02X919320Y384207I0J3502D01*
G01X919295Y384258D01*
X919201Y384317D01*
X918732Y384324D01*
X918637Y384268D01*
X918610Y384218D01*
G02X915525Y382374I-3085J1659D01*
G02X914106Y382675I2J3503D01*
G03X913944I-81J-183D01*
G02X912525Y382374I-1421J3202D01*
G02X909894Y383565I1J3503D01*
G01X909865Y383598D01*
X909787Y383633D01*
X909400D01*
X909322Y383598D01*
X909293Y383565D01*
G02X906662Y382374I-2632J2312D01*
G02X905243Y382675I2J3503D01*
G03X905081I-81J-183D01*
G02X903662Y382374I-1421J3202D01*
G02Y389380I0J3503D01*
G02X905081Y389079I-2J-3503D01*
G03X905243I81J183D01*
G02X906662Y389380I1421J-3202D01*
G02X909293Y388189I-1J-3503D01*
G01X909322Y388156D01*
X909400Y388121D01*
X909787D01*
X909865Y388156D01*
X909894Y388189D01*
G02X912525Y389380I2632J-2312D01*
G02X913944Y389079I-2J-3503D01*
G03X914106I81J183D01*
G02X915525Y389380I1421J-3202D01*
G02X918659Y387441I0J-3502D01*
G01X918684Y387390D01*
X918778Y387331D01*
X919247Y387324D01*
X919342Y387380D01*
X919369Y387430D01*
G02X922454Y389274I3085J-1659D01*
G02X923873Y388973I-2J-3503D01*
G03X924035I81J183D01*
G02X925454Y389274I1421J-3202D01*
G02X928085Y388083I-1J-3503D01*
G01X928114Y388050D01*
X928192Y388015D01*
X928579D01*
X928657Y388050D01*
X928686Y388083D01*
G02X931317Y389274I2632J-2312D01*
G02X932736Y388973I-2J-3503D01*
G03X932898I81J183D01*
G02X934317Y389274I1421J-3202D01*
G02X937402Y387429I0J-3502D01*
G01X937429Y387379D01*
X937525Y387323D01*
X937993Y387330D01*
X938087Y387389D01*
X938112Y387440D01*
G02X941247Y389380I3135J-1563D01*
G02X942666Y389079I-2J-3503D01*
G03X942828I81J183D01*
G02X944247Y389380I1421J-3202D01*
G02X946878Y388189I-1J-3503D01*
G01X946907Y388156D01*
X946985Y388121D01*
G37*
G36*
G01X853128Y388122D02*
X853515D01*
X853593Y388157D01*
X853622Y388190D01*
G02X856253Y389380I2630J-2312D01*
G02X857672Y389080I1J-3502D01*
G03X857834I81J183D01*
G02X859253Y389380I1418J-3202D01*
G02X862110Y387903I0J-3502D01*
G01X862138Y387864D01*
X862222Y387820D01*
X862641Y387813D01*
X862726Y387854D01*
X862755Y387892D01*
G02X865542Y389274I2788J-2121D01*
G02X866961Y388973I-2J-3503D01*
G03X867123I81J183D01*
G02X868542Y389274I1421J-3202D01*
G02X871173Y388083I-1J-3503D01*
G01X871202Y388050D01*
X871280Y388015D01*
X871667D01*
X871745Y388050D01*
X871774Y388083D01*
G02X874405Y389274I2632J-2312D01*
G02X875824Y388973I-2J-3503D01*
G03X875986I81J183D01*
G02X877405Y389274I1421J-3202D01*
G02X880467Y387472I0J-3503D01*
G03X880642Y387369I175J97D01*
G01X880991D01*
G03X881166Y387472I0J200D01*
G02X884228Y389274I3062J-1701D01*
G02X885647Y388973I-2J-3503D01*
G03X885809I81J183D01*
G02X887228Y389274I1421J-3202D01*
G02X889859Y388083I-1J-3503D01*
G01X889888Y388050D01*
X889966Y388015D01*
X890353D01*
X890431Y388050D01*
X890460Y388083D01*
G02X893091Y389274I2632J-2312D01*
G02X894510Y388973I-2J-3503D01*
G03X894672I81J183D01*
G02X896091Y389274I1421J-3202D01*
G02Y382268I0J-3503D01*
G02X894672Y382569I2J3503D01*
G03X894510I-81J-183D01*
G02X893091Y382268I-1421J3202D01*
G02X890460Y383459I1J3503D01*
G01X890431Y383492D01*
X890353Y383527D01*
X889966D01*
X889888Y383492D01*
X889859Y383459D01*
G02X887228Y382268I-2632J2312D01*
G02X885809Y382569I2J3503D01*
G03X885647I-81J-183D01*
G02X884228Y382268I-1421J3202D01*
G02X881166Y384070I0J3503D01*
G03X880991Y384173I-175J-97D01*
G01X880642D01*
G03X880467Y384070I0J-200D01*
G02X877405Y382268I-3062J1701D01*
G02X875986Y382569I2J3503D01*
G03X875824I-81J-183D01*
G02X874405Y382268I-1421J3202D01*
G02X871774Y383459I1J3503D01*
G01X871745Y383492D01*
X871667Y383527D01*
X871280D01*
X871202Y383492D01*
X871173Y383459D01*
G02X868542Y382268I-2632J2312D01*
G02X867123Y382569I2J3503D01*
G03X866961I-81J-183D01*
G02X865542Y382268I-1421J3202D01*
G02X862685Y383746I1J3502D01*
G01X862657Y383785D01*
X862573Y383829D01*
X862154Y383836D01*
X862069Y383795D01*
X862040Y383757D01*
G02X859253Y382376I-2787J2122D01*
G02X857834Y382676I-1J3502D01*
G03X857672I-81J-183D01*
G02X856253Y382376I-1418J3202D01*
G02X853622Y383566I-1J3502D01*
G01X853593Y383599D01*
X853515Y383634D01*
X853128D01*
X853050Y383599D01*
X853021Y383566D01*
G02X850390Y382376I-2630J2312D01*
G02X848971Y382676I-1J3502D01*
G03X848809I-81J-183D01*
G02X847390Y382376I-1418J3202D01*
G02Y389380I0J3502D01*
G02X848809Y389080I1J-3502D01*
G03X848971I81J183D01*
G02X850390Y389380I1418J-3202D01*
G02X853021Y388190I1J-3502D01*
G01X853050Y388157D01*
X853128Y388122D01*
G37*
G36*
G01X1071582Y404036D02*
X1071738Y404469D01*
X1071718Y404575D01*
X1071682Y404617D01*
G02X1070814Y406925I2634J2308D01*
G02X1077818I3502J0D01*
G02X1074872Y403467I-3502J0D01*
G01X1074817Y403458D01*
X1074734Y403389D01*
X1074578Y402956D01*
X1074598Y402850D01*
X1074634Y402808D01*
G02X1075502Y400500I-2634J-2308D01*
G02X1075202Y399081I-3502J-1D01*
G03Y398919I183J-81D01*
G02X1075502Y397500I-3202J-1418D01*
G02X1072000Y393998I-3502J0D01*
G02X1070581Y394298I-1J3502D01*
G03X1070419I-81J-183D01*
G02X1069611Y394051I-1420J3202D01*
G03X1069449Y393889I35J-197D01*
G02X1069202Y393081I-3449J612D01*
G03Y392919I183J-81D01*
G02X1069449Y392111I-3202J-1420D01*
G03X1069611Y391949I197J35D01*
G02X1070419Y391702I-612J-3449D01*
G03X1070581I81J183D01*
G02X1072000Y392002I1418J-3202D01*
G02X1075502Y388500I0J-3502D01*
G02X1075202Y387081I-3502J-1D01*
G03Y386919I183J-81D01*
G02X1075502Y385500I-3202J-1418D01*
G02X1072000Y381998I-3502J0D01*
G02X1070581Y382298I-1J3502D01*
G03X1070419I-81J-183D01*
G02X1069000Y381998I-1418J3202D01*
G02X1067581Y382298I-1J3502D01*
G03X1067419I-81J-183D01*
G02X1066000Y381998I-1418J3202D01*
G02X1064581Y382298I-1J3502D01*
G03X1064419I-81J-183D01*
G02X1063000Y381998I-1418J3202D01*
G02X1061581Y382298I-1J3502D01*
G03X1061419I-81J-183D01*
G02X1060000Y381998I-1418J3202D01*
G02X1056498Y385500I0J3502D01*
G02X1056798Y386919I3502J1D01*
G03Y387081I-183J81D01*
G02X1056498Y388500I3202J1418D01*
G02X1056798Y389919I3502J1D01*
G03Y390081I-183J81D01*
G02X1056498Y391500I3202J1418D01*
G02X1056798Y392919I3502J1D01*
G03Y393081I-183J81D01*
G02X1056498Y394500I3202J1418D01*
G02X1056798Y395919I3502J1D01*
G03Y396081I-183J81D01*
G02X1056498Y397500I3202J1418D01*
G02X1056798Y398919I3502J1D01*
G03Y399081I-183J81D01*
G02X1056498Y400500I3202J1418D01*
G02X1060000Y404002I3502J0D01*
G02X1061419Y403702I1J-3502D01*
G03X1061581I81J183D01*
G02X1063000Y404002I1418J-3202D01*
G02X1064419Y403702I1J-3502D01*
G03X1064581I81J183D01*
G02X1066000Y404002I1418J-3202D01*
G02X1067419Y403702I1J-3502D01*
G03X1067581I81J183D01*
G02X1069000Y404002I1418J-3202D01*
G02X1070419Y403702I1J-3502D01*
G03X1070581I81J183D01*
G02X1071444Y403958I1419J-3202D01*
G01X1071499Y403967D01*
X1071582Y404036D01*
G37*
G36*
G01X806904Y420118D02*
G02X808323Y420418I1418J-3202D01*
G02X809742Y420118I1J-3502D01*
G03X809904I81J183D01*
G02X811323Y420418I1418J-3202D01*
G02X812742Y420118I1J-3502D01*
G03X812904I81J183D01*
G02X814323Y420418I1418J-3202D01*
G02X815723Y420126I0J-3502D01*
G03X815876Y420123I80J184D01*
G02X817153Y420364I1277J-3261D01*
G02X820656Y416862I1J-3502D01*
G02X820355Y415443I-3503J2D01*
G03Y415281I183J-81D01*
G02X820656Y413862I-3202J-1421D01*
G02X820402Y412554I-3503J2D01*
G03Y412404I186J-75D01*
G02X820656Y411096I-3249J-1310D01*
G02X820355Y409677I-3503J2D01*
G03Y409515I183J-81D01*
G02X820656Y408096I-3202J-1421D01*
G02X820355Y406677I-3503J2D01*
G03Y406515I183J-81D01*
G02X820656Y405096I-3202J-1421D01*
G02X817153Y401594I-3503J1D01*
G02X815753Y401886I0J3502D01*
G03X815600Y401889I-80J-184D01*
G02X814323Y401648I-1277J3261D01*
G02X812904Y401948I-1J3502D01*
G03X812742I-81J-183D01*
G02X811323Y401648I-1418J3202D01*
G02X809904Y401948I-1J3502D01*
G03X809742I-81J-183D01*
G02X808323Y401648I-1418J3202D01*
G02X806904Y401948I-1J3502D01*
G03X806742I-81J-183D01*
G02X805323Y401648I-1418J3202D01*
G02X803904Y401948I-1J3502D01*
G03X803742I-81J-183D01*
G02X802323Y401648I-1418J3202D01*
G02X800904Y401948I-1J3502D01*
G03X800742I-81J-183D01*
G02X799323Y401648I-1418J3202D01*
G02X798098Y401869I-1J3502D01*
G03X797951Y401866I-70J-188D01*
G02X796600Y401594I-1353J3231D01*
G02X793098Y405097I1J3503D01*
G02X793398Y406516I3502J1D01*
G03Y406678I-183J81D01*
G02X793098Y408097I3202J1418D01*
G02X793398Y409516I3502J1D01*
G03Y409678I-183J81D01*
G02X793098Y411097I3202J1418D01*
G02X793351Y412405I3502J1D01*
G03Y412555I-186J75D01*
G02X793098Y413863I3249J1307D01*
G02X793398Y415282I3502J1D01*
G03Y415444I-183J81D01*
G02X793098Y416863I3202J1418D01*
G02X796600Y420366I3502J1D01*
G02X797825Y420144I-2J-3503D01*
G03X797972Y420147I70J188D01*
G02X799323Y420418I1351J-3232D01*
G02X800742Y420118I1J-3502D01*
G03X800904I81J183D01*
G02X802323Y420418I1418J-3202D01*
G02X803742Y420118I1J-3502D01*
G03X803904I81J183D01*
G02X805323Y420418I1418J-3202D01*
G02X806742Y420118I1J-3502D01*
G03X806904I81J183D01*
G37*
G36*
G01X863923D02*
G02X865342Y420418I1418J-3202D01*
G02X866761Y420118I1J-3502D01*
G03X866923I81J183D01*
G02X868342Y420418I1418J-3202D01*
G02X869761Y420118I1J-3502D01*
G03X869923I81J183D01*
G02X871342Y420418I1418J-3202D01*
G02X872742Y420126I0J-3502D01*
G03X872895Y420123I80J184D01*
G02X874172Y420364I1277J-3261D01*
G02X877674Y416862I0J-3502D01*
G02X877374Y415443I-3502J-1D01*
G03Y415281I183J-81D01*
G02X877674Y413862I-3202J-1418D01*
G02X877421Y412554I-3502J-1D01*
G03Y412404I186J-75D01*
G02X877674Y411096I-3249J-1307D01*
G02X877374Y409677I-3502J-1D01*
G03Y409515I183J-81D01*
G02X877674Y408096I-3202J-1418D01*
G02X877374Y406677I-3502J-1D01*
G03Y406515I183J-81D01*
G02X877674Y405096I-3202J-1418D01*
G02X874172Y401594I-3502J0D01*
G02X872772Y401886I0J3502D01*
G03X872619Y401889I-80J-184D01*
G02X871342Y401648I-1277J3261D01*
G02X869923Y401948I-1J3502D01*
G03X869761I-81J-183D01*
G02X868342Y401648I-1418J3202D01*
G02X866923Y401948I-1J3502D01*
G03X866761I-81J-183D01*
G02X865342Y401648I-1418J3202D01*
G02X863923Y401948I-1J3502D01*
G03X863761I-81J-183D01*
G02X862342Y401648I-1418J3202D01*
G02X860923Y401948I-1J3502D01*
G03X860761I-81J-183D01*
G02X859342Y401648I-1418J3202D01*
G02X857923Y401948I-1J3502D01*
G03X857761I-81J-183D01*
G02X856342Y401648I-1418J3202D01*
G02X855117Y401869I-1J3502D01*
G03X854970Y401866I-70J-188D01*
G02X853619Y401594I-1353J3231D01*
G02X850116Y405097I0J3503D01*
G02X850417Y406516I3503J-2D01*
G03Y406678I-183J81D01*
G02X850116Y408097I3202J1421D01*
G02X850417Y409516I3503J-2D01*
G03Y409678I-183J81D01*
G02X850116Y411097I3202J1421D01*
G02X850370Y412405I3503J-2D01*
G03Y412555I-186J75D01*
G02X850116Y413863I3249J1310D01*
G02X850417Y415282I3503J-2D01*
G03Y415444I-183J81D01*
G02X850116Y416863I3202J1421D01*
G02X853619Y420366I3503J0D01*
G02X854844Y420144I-2J-3503D01*
G03X854991Y420147I70J188D01*
G02X856342Y420418I1351J-3232D01*
G02X857761Y420118I1J-3502D01*
G03X857923I81J183D01*
G02X859342Y420418I1418J-3202D01*
G02X860761Y420118I1J-3502D01*
G03X860923I81J183D01*
G02X862342Y420418I1418J-3202D01*
G02X863761Y420118I1J-3502D01*
G03X863923I81J183D01*
G37*
G36*
G01X112520Y422234D02*
G02X112198Y423700I3180J1467D01*
G02X112498Y425119I3502J1D01*
G03Y425281I-182J81D01*
G02X112198Y426700I3202J1418D01*
G02X115700Y430202I3502J0D01*
G02X117576Y429657I0J-3501D01*
G03X117782Y429651I108J169D01*
G02X119500Y430102I1719J-3051D01*
G02X121155Y429686I0J-3502D01*
G03X121345I95J176D01*
G02X123000Y430102I1655J-3086D01*
G02X126502Y426600I0J-3502D01*
G02X126202Y425181I-3502J-1D01*
G03Y425019I182J-81D01*
G02X126502Y423600I-3202J-1418D01*
G02X126181Y422134I-3502J-1D01*
G03Y421967I181J-84D01*
G02X126502Y420500I-3181J-1465D01*
G02X126202Y419081I-3502J-1D01*
G03Y418919I183J-81D01*
G02X126502Y417500I-3202J-1418D01*
G02X126202Y416081I-3502J-1D01*
G03Y415919I183J-81D01*
G02X126502Y414500I-3202J-1418D01*
G02X126202Y413081I-3502J-1D01*
G03Y412919I183J-81D01*
G02X126502Y411500I-3202J-1418D01*
G02X126202Y410081I-3502J-1D01*
G03Y409919I183J-81D01*
G02X126502Y408500I-3202J-1418D01*
G02X123000Y404998I-3502J0D01*
G02X121345Y405413I-1J3502D01*
G03X121155I-95J-176D01*
G02X119500Y404998I-1654J3087D01*
G02X117623Y405543I-1J3502D01*
G03X117418Y405548I-107J-169D01*
G02X115700Y405098I-1717J3052D01*
G02X112198Y408600I0J3502D01*
G02X112498Y410019I3502J1D01*
G03Y410181I-182J81D01*
G02X112198Y411600I3202J1418D01*
G02X112498Y413019I3502J1D01*
G03Y413181I-182J81D01*
G02X112198Y414600I3202J1418D01*
G02X112498Y416019I3502J1D01*
G03Y416181I-182J81D01*
G02X112198Y417600I3202J1418D01*
G02X112498Y419019I3502J1D01*
G03Y419181I-182J81D01*
G02X112198Y420600I3202J1418D01*
G02X112520Y422066I3502J-1D01*
G03Y422234I-182J84D01*
G37*
G36*
G01X153598Y425181D02*
G02X153298Y426600I3202J1418D01*
G02X156800Y430102I3502J0D01*
G02X158455Y429686I0J-3502D01*
G03X158645I95J176D01*
G02X160300Y430102I1655J-3086D01*
G02X161867Y429732I0J-3503D01*
G03X162056Y429737I90J179D01*
G02X163800Y430202I1744J-3038D01*
G02X167302Y426700I0J-3502D01*
G02X167002Y425281I-3502J-1D01*
G03Y425119I182J-81D01*
G02X167302Y423700I-3202J-1418D01*
G02X167067Y422438I-3502J-1D01*
G03X167078Y422271I187J-72D01*
G02X167502Y420600I-3078J-1670D01*
G02X167202Y419181I-3502J-1D01*
G03Y419019I182J-81D01*
G02X167502Y417600I-3202J-1418D01*
G02X167202Y416181I-3502J-1D01*
G03Y416019I182J-81D01*
G02X167502Y414600I-3202J-1418D01*
G02X167202Y413181I-3502J-1D01*
G03Y413019I182J-81D01*
G02X167502Y411600I-3202J-1418D01*
G02X167202Y410181I-3502J-1D01*
G03Y410019I182J-81D01*
G02X167502Y408600I-3202J-1418D01*
G02X164000Y405098I-3502J0D01*
G02X162433Y405468I0J3503D01*
G03X162244Y405463I-90J-179D01*
G02X160500Y404998I-1744J3038D01*
G02X158845Y405413I-1J3502D01*
G03X158655I-95J-176D01*
G02X157000Y404998I-1654J3087D01*
G02X153498Y408500I0J3502D01*
G02X153798Y409919I3502J1D01*
G03Y410081I-183J81D01*
G02X153498Y411500I3202J1418D01*
G02X153798Y412919I3502J1D01*
G03Y413081I-183J81D01*
G02X153498Y414500I3202J1418D01*
G02X153798Y415919I3502J1D01*
G03Y416081I-183J81D01*
G02X153498Y417500I3202J1418D01*
G02X153798Y418919I3502J1D01*
G03Y419081I-183J81D01*
G02X153498Y420500I3202J1418D01*
G02X153733Y421762I3502J1D01*
G03X153722Y421930I-187J72D01*
G02X153298Y423600I3077J1670D01*
G02X153598Y425019I3502J1D01*
G03Y425181I-182J81D01*
G37*
G36*
G01X563318Y445297D02*
G02X564500Y445502I1181J-3297D01*
G02Y438498I0J-3502D01*
G02X563318Y438703I-1J3502D01*
G03X563182I-68J-188D01*
G02X562000Y438498I-1181J3297D01*
G02Y445502I0J3502D01*
G02X563182Y445297I1J-3502D01*
G03X563318I68J188D01*
G37*
G36*
G01X1064581Y451202D02*
G02X1066000Y451502I1418J-3202D01*
G02X1067419Y451202I1J-3502D01*
G03X1067581I81J183D01*
G02X1069000Y451502I1418J-3202D01*
G02X1070419Y451202I1J-3502D01*
G03X1070581I81J183D01*
G02X1072000Y451502I1418J-3202D01*
G02X1075502Y448000I0J-3502D01*
G02X1075202Y446581I-3502J-1D01*
G03Y446419I183J-81D01*
G02X1075502Y445000I-3202J-1418D01*
G02X1072000Y441498I-3502J0D01*
G02X1070581Y441798I-1J3502D01*
G03X1070419I-81J-183D01*
G02X1069611Y441551I-1420J3202D01*
G03X1069449Y441389I35J-197D01*
G02X1069202Y440581I-3449J612D01*
G03Y440419I183J-81D01*
G02X1069449Y439611I-3202J-1420D01*
G03X1069611Y439449I197J35D01*
G02X1070419Y439202I-612J-3449D01*
G03X1070581I81J183D01*
G02X1072000Y439502I1418J-3202D01*
G02X1075502Y436000I0J-3502D01*
G02X1075202Y434581I-3502J-1D01*
G03Y434419I183J-81D01*
G02X1075502Y433000I-3202J-1418D01*
G02X1072000Y429498I-3502J0D01*
G02X1070581Y429798I-1J3502D01*
G03X1070419I-81J-183D01*
G02X1069000Y429498I-1418J3202D01*
G02X1067581Y429798I-1J3502D01*
G03X1067419I-81J-183D01*
G02X1066000Y429498I-1418J3202D01*
G02X1064581Y429798I-1J3502D01*
G03X1064419I-81J-183D01*
G02X1063000Y429498I-1418J3202D01*
G02X1061581Y429798I-1J3502D01*
G03X1061419I-81J-183D01*
G02X1060000Y429498I-1418J3202D01*
G02X1056498Y433000I0J3502D01*
G02X1056798Y434419I3502J1D01*
G03Y434581I-183J81D01*
G02X1056498Y436000I3202J1418D01*
G02X1056798Y437419I3502J1D01*
G03Y437581I-183J81D01*
G02X1056498Y439000I3202J1418D01*
G02X1056798Y440419I3502J1D01*
G03Y440581I-183J81D01*
G02X1056498Y442000I3202J1418D01*
G02X1056798Y443419I3502J1D01*
G03Y443581I-183J81D01*
G02X1056498Y445000I3202J1418D01*
G02X1056798Y446419I3502J1D01*
G03Y446581I-183J81D01*
G02X1056498Y448000I3202J1418D01*
G02X1060000Y451502I3502J0D01*
G02X1061419Y451202I1J-3502D01*
G03X1061581I81J183D01*
G02X1063000Y451502I1418J-3202D01*
G02X1064419Y451202I1J-3502D01*
G03X1064581I81J183D01*
G37*
G36*
G01X810290Y489534D02*
G02X811709Y489834I1418J-3202D01*
G02X813128Y489534I1J-3502D01*
G03X813290I81J183D01*
G02X814709Y489834I1418J-3202D01*
G02X816128Y489534I1J-3502D01*
G03X816290I81J183D01*
G02X817709Y489834I1418J-3202D01*
G02X821212Y486332I1J-3502D01*
G02X820920Y484932I-3502J0D01*
G03X820917Y484779I183J-80D01*
G02X821158Y483503I-3262J-1277D01*
G02X820857Y482084I-3503J2D01*
G03Y481922I183J-81D01*
G02X821158Y480503I-3202J-1421D01*
G02X820894Y479170I-3503J1D01*
G03Y479017I185J-76D01*
G02X821158Y477684I-3239J-1334D01*
G02X820857Y476265I-3503J2D01*
G03Y476103I183J-81D01*
G02X821158Y474684I-3202J-1421D01*
G02X817655Y471182I-3503J1D01*
G02X816236Y471482I-1J3502D01*
G03X816074I-81J-183D01*
G02X814655Y471182I-1418J3202D01*
G02X813236Y471482I-1J3502D01*
G03X813074I-81J-183D01*
G02X811655Y471182I-1418J3202D01*
G02X810236Y471482I-1J3502D01*
G03X810074I-81J-183D01*
G02X808655Y471182I-1418J3202D01*
G02X807236Y471482I-1J3502D01*
G03X807074I-81J-183D01*
G02X805655Y471182I-1418J3202D01*
G02X804236Y471482I-1J3502D01*
G03X804074I-81J-183D01*
G02X802655Y471182I-1418J3202D01*
G02X801236Y471482I-1J3502D01*
G03X801074I-81J-183D01*
G02X799655Y471182I-1418J3202D01*
G02X798236Y471482I-1J3502D01*
G03X798074I-81J-183D01*
G02X796655Y471182I-1418J3202D01*
G02X793152Y474684I-1J3502D01*
G02X793453Y476103I3503J-2D01*
G03Y476265I-183J81D01*
G02X793152Y477684I3202J1421D01*
G02X793416Y479017I3503J-1D01*
G03Y479170I-185J77D01*
G02X793152Y480503I3239J1334D01*
G02X793453Y481922I3503J-2D01*
G03Y482084I-183J81D01*
G02X793152Y483503I3202J1421D01*
G02X793444Y484903I3502J0D01*
G03X793447Y485056I-183J80D01*
G02X793206Y486332I3262J1277D01*
G02X796709Y489834I3503J-1D01*
G02X798128Y489534I1J-3502D01*
G03X798290I81J183D01*
G02X799709Y489834I1418J-3202D01*
G02X801128Y489534I1J-3502D01*
G03X801290I81J183D01*
G02X802709Y489834I1418J-3202D01*
G02X804128Y489534I1J-3502D01*
G03X804290I81J183D01*
G02X805709Y489834I1418J-3202D01*
G02X807128Y489534I1J-3502D01*
G03X807290I81J183D01*
G02X808709Y489834I1418J-3202D01*
G02X810128Y489534I1J-3502D01*
G03X810290I81J183D01*
G37*
G36*
G01X866892D02*
G02X868311Y489834I1418J-3202D01*
G02X869730Y489534I1J-3502D01*
G03X869892I81J183D01*
G02X871311Y489834I1418J-3202D01*
G02X872730Y489534I1J-3502D01*
G03X872892I81J183D01*
G02X874311Y489834I1418J-3202D01*
G02X877814Y486332I1J-3502D01*
G02X877522Y484932I-3502J0D01*
G03X877519Y484779I183J-80D01*
G02X877760Y483503I-3262J-1277D01*
G02X877459Y482084I-3503J2D01*
G03Y481922I183J-81D01*
G02X877760Y480503I-3202J-1421D01*
G02X877496Y479170I-3503J1D01*
G03Y479017I185J-76D01*
G02X877760Y477684I-3239J-1334D01*
G02X877459Y476265I-3503J2D01*
G03Y476103I183J-81D01*
G02X877760Y474684I-3202J-1421D01*
G02X874257Y471182I-3503J1D01*
G02X872838Y471482I-1J3502D01*
G03X872676I-81J-183D01*
G02X871257Y471182I-1418J3202D01*
G02X869838Y471482I-1J3502D01*
G03X869676I-81J-183D01*
G02X868257Y471182I-1418J3202D01*
G02X866838Y471482I-1J3502D01*
G03X866676I-81J-183D01*
G02X865257Y471182I-1418J3202D01*
G02X863838Y471482I-1J3502D01*
G03X863676I-81J-183D01*
G02X862257Y471182I-1418J3202D01*
G02X860838Y471482I-1J3502D01*
G03X860676I-81J-183D01*
G02X859257Y471182I-1418J3202D01*
G02X857838Y471482I-1J3502D01*
G03X857676I-81J-183D01*
G02X856257Y471182I-1418J3202D01*
G02X854838Y471482I-1J3502D01*
G03X854676I-81J-183D01*
G02X853257Y471182I-1418J3202D01*
G02X849754Y474684I-1J3502D01*
G02X850055Y476103I3503J-2D01*
G03Y476265I-183J81D01*
G02X849754Y477684I3202J1421D01*
G02X850018Y479017I3503J-1D01*
G03Y479170I-185J77D01*
G02X849754Y480503I3239J1334D01*
G02X850055Y481922I3503J-2D01*
G03Y482084I-183J81D01*
G02X849754Y483503I3202J1421D01*
G02X850046Y484903I3502J0D01*
G03X850049Y485056I-183J80D01*
G02X849808Y486332I3262J1277D01*
G02X853311Y489834I3503J-1D01*
G02X854730Y489534I1J-3502D01*
G03X854892I81J183D01*
G02X856311Y489834I1418J-3202D01*
G02X857730Y489534I1J-3502D01*
G03X857892I81J183D01*
G02X859311Y489834I1418J-3202D01*
G02X860730Y489534I1J-3502D01*
G03X860892I81J183D01*
G02X862311Y489834I1418J-3202D01*
G02X863730Y489534I1J-3502D01*
G03X863892I81J183D01*
G02X865311Y489834I1418J-3202D01*
G02X866730Y489534I1J-3502D01*
G03X866892I81J183D01*
G37*
G36*
G01X68400Y475573D02*
X67972Y475638D01*
X67879Y475606D01*
X67844Y475568D01*
G02Y488842I-7214J6637D01*
G01X67879Y488804D01*
X67972Y488772D01*
X68400Y488837D01*
X68479Y488896D01*
X68500Y488942D01*
G02X82795Y498008I14295J-6737D01*
G02Y466402I0J-15803D01*
G02X68500Y475468I0J15803D01*
G01X68479Y475514D01*
X68400Y475573D01*
G37*
G36*
G01X1064581Y498702D02*
G02X1066000Y499002I1418J-3202D01*
G02X1067419Y498702I1J-3502D01*
G03X1067581I81J183D01*
G02X1069000Y499002I1418J-3202D01*
G02X1070419Y498702I1J-3502D01*
G03X1070581I81J183D01*
G02X1072000Y499002I1418J-3202D01*
G02X1075502Y495500I0J-3502D01*
G02X1075202Y494081I-3502J-1D01*
G03Y493919I183J-81D01*
G02X1075502Y492500I-3202J-1418D01*
G02X1072000Y488998I-3502J0D01*
G02X1070581Y489298I-1J3502D01*
G03X1070419I-81J-183D01*
G02X1069611Y489051I-1420J3202D01*
G03X1069449Y488889I35J-197D01*
G02X1069202Y488081I-3449J612D01*
G03Y487919I183J-81D01*
G02X1069449Y487111I-3202J-1420D01*
G03X1069611Y486949I197J35D01*
G02X1070419Y486702I-612J-3449D01*
G03X1070581I81J183D01*
G02X1072000Y487002I1418J-3202D01*
G02X1075502Y483500I0J-3502D01*
G02X1075202Y482081I-3502J-1D01*
G03Y481919I183J-81D01*
G02X1075502Y480500I-3202J-1418D01*
G02X1072000Y476998I-3502J0D01*
G02X1070581Y477298I-1J3502D01*
G03X1070419I-81J-183D01*
G02X1069000Y476998I-1418J3202D01*
G02X1067581Y477298I-1J3502D01*
G03X1067419I-81J-183D01*
G02X1066000Y476998I-1418J3202D01*
G02X1064581Y477298I-1J3502D01*
G03X1064419I-81J-183D01*
G02X1063000Y476998I-1418J3202D01*
G02X1061581Y477298I-1J3502D01*
G03X1061419I-81J-183D01*
G02X1060000Y476998I-1418J3202D01*
G02X1056498Y480500I0J3502D01*
G02X1056798Y481919I3502J1D01*
G03Y482081I-183J81D01*
G02X1056498Y483500I3202J1418D01*
G02X1056798Y484919I3502J1D01*
G03Y485081I-183J81D01*
G02X1056498Y486500I3202J1418D01*
G02X1056798Y487919I3502J1D01*
G03Y488081I-183J81D01*
G02X1056498Y489500I3202J1418D01*
G02X1056798Y490919I3502J1D01*
G03Y491081I-183J81D01*
G02X1056498Y492500I3202J1418D01*
G02X1056798Y493919I3502J1D01*
G03Y494081I-183J81D01*
G02X1056498Y495500I3202J1418D01*
G02X1060000Y499002I3502J0D01*
G02X1061419Y498702I1J-3502D01*
G03X1061581I81J183D01*
G02X1063000Y499002I1418J-3202D01*
G02X1064419Y498702I1J-3502D01*
G03X1064581I81J183D01*
G37*
G36*
G01X170520Y501202D02*
G02X171939Y501502I1418J-3202D01*
G02Y494498I0J-3502D01*
G02X170520Y494798I-1J3502D01*
G03X170358I-81J-183D01*
G02X168939Y494498I-1418J3202D01*
G02Y501502I0J3502D01*
G02X170358Y501202I1J-3502D01*
G03X170520I81J183D01*
G37*
G36*
G01X218520D02*
G02X219939Y501502I1418J-3202D01*
G02Y494498I0J-3502D01*
G02X218520Y494798I-1J3502D01*
G03X218358I-81J-183D01*
G02X216939Y494498I-1418J3202D01*
G02Y501502I0J3502D01*
G02X218358Y501202I1J-3502D01*
G03X218520I81J183D01*
G37*
G36*
G01X266520D02*
G02X267939Y501502I1418J-3202D01*
G02Y494498I0J-3502D01*
G02X266520Y494798I-1J3502D01*
G03X266358I-81J-183D01*
G02X264939Y494498I-1418J3202D01*
G02Y501502I0J3502D01*
G02X266358Y501202I1J-3502D01*
G03X266520I81J183D01*
G37*
G36*
G01X328000D02*
G02X329419Y501502I1418J-3202D01*
G02Y494498I0J-3502D01*
G02X328000Y494798I-1J3502D01*
G03X327838I-81J-183D01*
G02X326419Y494498I-1418J3202D01*
G02Y501502I0J3502D01*
G02X327838Y501202I1J-3502D01*
G03X328000I81J183D01*
G37*
G36*
G01X376000D02*
G02X377419Y501502I1418J-3202D01*
G02Y494498I0J-3502D01*
G02X376000Y494798I-1J3502D01*
G03X375838I-81J-183D01*
G02X374419Y494498I-1418J3202D01*
G02Y501502I0J3502D01*
G02X375838Y501202I1J-3502D01*
G03X376000I81J183D01*
G37*
G36*
G01X424000D02*
G02X425419Y501502I1418J-3202D01*
G02Y494498I0J-3502D01*
G02X424000Y494798I-1J3502D01*
G03X423838I-81J-183D01*
G02X422419Y494498I-1418J3202D01*
G02Y501502I0J3502D01*
G02X423838Y501202I1J-3502D01*
G03X424000I81J183D01*
G37*
G36*
G01X485481D02*
G02X486900Y501502I1418J-3202D01*
G02Y494498I0J-3502D01*
G02X485481Y494798I-1J3502D01*
G03X485319I-81J-183D01*
G02X483900Y494498I-1418J3202D01*
G02Y501502I0J3502D01*
G02X485319Y501202I1J-3502D01*
G03X485481I81J183D01*
G37*
G36*
G01X533481D02*
G02X534900Y501502I1418J-3202D01*
G02Y494498I0J-3502D01*
G02X533481Y494798I-1J3502D01*
G03X533319I-81J-183D01*
G02X531900Y494498I-1418J3202D01*
G02Y501502I0J3502D01*
G02X533319Y501202I1J-3502D01*
G03X533481I81J183D01*
G37*
G36*
G01X581481D02*
G02X582900Y501502I1418J-3202D01*
G02Y494498I0J-3502D01*
G02X581481Y494798I-1J3502D01*
G03X581319I-81J-183D01*
G02X579900Y494498I-1418J3202D01*
G02Y501502I0J3502D01*
G02X581319Y501202I1J-3502D01*
G03X581481I81J183D01*
G37*
G36*
G01X642962D02*
G02X644381Y501502I1418J-3202D01*
G02Y494498I0J-3502D01*
G02X642962Y494798I-1J3502D01*
G03X642800I-81J-183D01*
G02X641381Y494498I-1418J3202D01*
G02Y501502I0J3502D01*
G02X642800Y501202I1J-3502D01*
G03X642962I81J183D01*
G37*
G36*
G01X690962D02*
G02X692381Y501502I1418J-3202D01*
G02Y494498I0J-3502D01*
G02X690962Y494798I-1J3502D01*
G03X690800I-81J-183D01*
G02X689381Y494498I-1418J3202D01*
G02Y501502I0J3502D01*
G02X690800Y501202I1J-3502D01*
G03X690962I81J183D01*
G37*
G36*
G01X738962D02*
G02X740381Y501502I1418J-3202D01*
G02Y494498I0J-3502D01*
G02X738962Y494798I-1J3502D01*
G03X738800I-81J-183D01*
G02X737381Y494498I-1418J3202D01*
G02Y501502I0J3502D01*
G02X738800Y501202I1J-3502D01*
G03X738962I81J183D01*
G37*
G36*
G01X170520Y521202D02*
G02X171939Y521502I1418J-3202D01*
G02Y514498I0J-3502D01*
G02X170520Y514798I-1J3502D01*
G03X170358I-81J-183D01*
G02X168939Y514498I-1418J3202D01*
G02Y521502I0J3502D01*
G02X170358Y521202I1J-3502D01*
G03X170520I81J183D01*
G37*
G36*
G01X218520D02*
G02X219939Y521502I1418J-3202D01*
G02Y514498I0J-3502D01*
G02X218520Y514798I-1J3502D01*
G03X218358I-81J-183D01*
G02X216939Y514498I-1418J3202D01*
G02Y521502I0J3502D01*
G02X218358Y521202I1J-3502D01*
G03X218520I81J183D01*
G37*
G36*
G01X266520D02*
G02X267939Y521502I1418J-3202D01*
G02Y514498I0J-3502D01*
G02X266520Y514798I-1J3502D01*
G03X266358I-81J-183D01*
G02X264939Y514498I-1418J3202D01*
G02Y521502I0J3502D01*
G02X266358Y521202I1J-3502D01*
G03X266520I81J183D01*
G37*
G36*
G01X328000D02*
G02X329419Y521502I1418J-3202D01*
G02Y514498I0J-3502D01*
G02X328000Y514798I-1J3502D01*
G03X327838I-81J-183D01*
G02X326419Y514498I-1418J3202D01*
G02Y521502I0J3502D01*
G02X327838Y521202I1J-3502D01*
G03X328000I81J183D01*
G37*
G36*
G01X376000D02*
G02X377419Y521502I1418J-3202D01*
G02Y514498I0J-3502D01*
G02X376000Y514798I-1J3502D01*
G03X375838I-81J-183D01*
G02X374419Y514498I-1418J3202D01*
G02Y521502I0J3502D01*
G02X375838Y521202I1J-3502D01*
G03X376000I81J183D01*
G37*
G36*
G01X424000D02*
G02X425419Y521502I1418J-3202D01*
G02Y514498I0J-3502D01*
G02X424000Y514798I-1J3502D01*
G03X423838I-81J-183D01*
G02X422419Y514498I-1418J3202D01*
G02Y521502I0J3502D01*
G02X423838Y521202I1J-3502D01*
G03X424000I81J183D01*
G37*
G36*
G01X485481D02*
G02X486900Y521502I1418J-3202D01*
G02Y514498I0J-3502D01*
G02X485481Y514798I-1J3502D01*
G03X485319I-81J-183D01*
G02X483900Y514498I-1418J3202D01*
G02Y521502I0J3502D01*
G02X485319Y521202I1J-3502D01*
G03X485481I81J183D01*
G37*
G36*
G01X533481D02*
G02X534900Y521502I1418J-3202D01*
G02Y514498I0J-3502D01*
G02X533481Y514798I-1J3502D01*
G03X533319I-81J-183D01*
G02X531900Y514498I-1418J3202D01*
G02Y521502I0J3502D01*
G02X533319Y521202I1J-3502D01*
G03X533481I81J183D01*
G37*
G36*
G01X581481D02*
G02X582900Y521502I1418J-3202D01*
G02Y514498I0J-3502D01*
G02X581481Y514798I-1J3502D01*
G03X581319I-81J-183D01*
G02X579900Y514498I-1418J3202D01*
G02Y521502I0J3502D01*
G02X581319Y521202I1J-3502D01*
G03X581481I81J183D01*
G37*
G36*
G01X642962D02*
G02X644381Y521502I1418J-3202D01*
G02Y514498I0J-3502D01*
G02X642962Y514798I-1J3502D01*
G03X642800I-81J-183D01*
G02X641381Y514498I-1418J3202D01*
G02Y521502I0J3502D01*
G02X642800Y521202I1J-3502D01*
G03X642962I81J183D01*
G37*
G36*
G01X690962D02*
G02X692381Y521502I1418J-3202D01*
G02Y514498I0J-3502D01*
G02X690962Y514798I-1J3502D01*
G03X690800I-81J-183D01*
G02X689381Y514498I-1418J3202D01*
G02Y521502I0J3502D01*
G02X690800Y521202I1J-3502D01*
G03X690962I81J183D01*
G37*
G36*
G01X738962D02*
G02X740381Y521502I1418J-3202D01*
G02Y514498I0J-3502D01*
G02X738962Y514798I-1J3502D01*
G03X738800I-81J-183D01*
G02X737381Y514498I-1418J3202D01*
G02Y521502I0J3502D01*
G02X738800Y521202I1J-3502D01*
G03X738962I81J183D01*
G37*
G36*
G01X916288Y522263D02*
G02X917596Y522516I1307J-3249D01*
G02X919015Y522216I1J-3502D01*
G03X919177I81J183D01*
G02X920596Y522516I1418J-3202D01*
G02X922015Y522216I1J-3502D01*
G03X922177I81J183D01*
G02X923596Y522516I1418J-3202D01*
G02X927098Y519014I0J-3502D01*
G02X926806Y517614I-3502J0D01*
G03X926803Y517461I184J-80D01*
G02X927044Y516184I-3261J-1277D01*
G02X926744Y514765I-3502J-1D01*
G03Y514603I183J-81D01*
G02X927044Y513184I-3202J-1418D01*
G02X926744Y511765I-3502J-1D01*
G03Y511603I183J-81D01*
G02X927044Y510184I-3202J-1418D01*
G02X926744Y508765I-3502J-1D01*
G03Y508603I183J-81D01*
G02X927044Y507184I-3202J-1418D01*
G02X926744Y505765I-3502J-1D01*
G03Y505603I183J-81D01*
G02X927044Y504184I-3202J-1418D01*
G02X926744Y502765I-3502J-1D01*
G03Y502603I183J-81D01*
G02X927044Y501184I-3202J-1418D01*
G02X926823Y499959I-3502J-1D01*
G03X926826Y499812I188J-70D01*
G02X927098Y498461I-3231J-1353D01*
G02X923595Y494958I-3503J0D01*
G02X922176Y495259I2J3503D01*
G03X922014I-81J-183D01*
G02X920595Y494958I-1421J3202D01*
G02X919176Y495259I2J3503D01*
G03X919014I-81J-183D01*
G02X917595Y494958I-1421J3202D01*
G02X916287Y495212I2J3503D01*
G03X916137I-75J-186D01*
G02X914829Y494958I-1310J3249D01*
G02X913410Y495259I2J3503D01*
G03X913248I-81J-183D01*
G02X911829Y494958I-1421J3202D01*
G02X908326Y498461I0J3503D01*
G02X908548Y499686I3503J-2D01*
G03X908545Y499833I-188J70D01*
G02X908274Y501184I3232J1351D01*
G02X908574Y502603I3502J1D01*
G03Y502765I-183J81D01*
G02X908274Y504184I3202J1418D01*
G02X908574Y505603I3502J1D01*
G03Y505765I-183J81D01*
G02X908274Y507184I3202J1418D01*
G02X908574Y508603I3502J1D01*
G03Y508765I-183J81D01*
G02X908274Y510184I3202J1418D01*
G02X908574Y511603I3502J1D01*
G03Y511765I-183J81D01*
G02X908274Y513184I3202J1418D01*
G02X908574Y514603I3502J1D01*
G03Y514765I-183J81D01*
G02X908274Y516184I3202J1418D01*
G02X908566Y517584I3502J0D01*
G03X908569Y517737I-184J80D01*
G02X908328Y519014I3261J1277D01*
G02X911830Y522516I3502J0D01*
G02X913249Y522216I1J-3502D01*
G03X913411I81J183D01*
G02X914830Y522516I1418J-3202D01*
G02X916138Y522263I1J-3502D01*
G03X916288I75J186D01*
G37*
G36*
G01X839232Y519045D02*
G02X838932Y520464I3202J1418D01*
G02X839232Y521883I3502J1D01*
G03Y522045I-183J81D01*
G02X838932Y523464I3202J1418D01*
G02X842434Y526966I3502J0D01*
G02X843834Y526675I2J-3502D01*
G03X843987Y526672I80J183D01*
G02X845263Y526912I1274J-3262D01*
G02X846682Y526612I1J-3502D01*
G03X846844I81J183D01*
G02X848263Y526912I1418J-3202D01*
G02X849596Y526649I1J-3502D01*
G03X849749I77J185D01*
G02X851082Y526912I1332J-3239D01*
G02X852501Y526612I1J-3502D01*
G03X852663I81J183D01*
G02X854082Y526912I1418J-3202D01*
G02X857584Y523410I0J-3502D01*
G02X857284Y521991I-3502J-1D01*
G03Y521829I183J-81D01*
G02X857584Y520410I-3202J-1418D01*
G02X857284Y518991I-3502J-1D01*
G03Y518829I183J-81D01*
G02X857584Y517410I-3202J-1418D01*
G02X857284Y515991I-3502J-1D01*
G03Y515829I183J-81D01*
G02X857584Y514410I-3202J-1418D01*
G02X857284Y512991I-3502J-1D01*
G03Y512829I183J-81D01*
G02X857584Y511410I-3202J-1418D01*
G02X857284Y509991I-3502J-1D01*
G03Y509829I183J-81D01*
G02X857584Y508410I-3202J-1418D01*
G02X857284Y506991I-3502J-1D01*
G03Y506829I183J-81D01*
G02X857584Y505410I-3202J-1418D01*
G02X857284Y503991I-3502J-1D01*
G03Y503829I183J-81D01*
G02X857584Y502410I-3202J-1418D01*
G02X854082Y498908I-3502J0D01*
G02X852663Y499208I-1J3502D01*
G03X852501I-81J-183D01*
G02X851082Y498908I-1418J3202D01*
G02X849749Y499171I-1J3502D01*
G03X849596I-76J-185D01*
G02X848263Y498908I-1332J3239D01*
G02X846844Y499208I-1J3502D01*
G03X846682I-81J-183D01*
G02X845263Y498908I-1418J3202D01*
G02X843863Y499199I-2J3502D01*
G03X843710Y499202I-80J-183D01*
G02X842434Y498962I-1274J3262D01*
G02X838932Y502464I0J3502D01*
G02X839232Y503883I3502J1D01*
G03Y504045I-183J81D01*
G02X838932Y505464I3202J1418D01*
G02X839232Y506883I3502J1D01*
G03Y507045I-183J81D01*
G02X838932Y508464I3202J1418D01*
G02X839232Y509883I3502J1D01*
G03Y510045I-183J81D01*
G02X838932Y511464I3202J1418D01*
G02X839232Y512883I3502J1D01*
G03Y513045I-183J81D01*
G02X838932Y514464I3202J1418D01*
G02X839232Y515883I3502J1D01*
G03Y516045I-183J81D01*
G02X838932Y517464I3202J1418D01*
G02X839232Y518883I3502J1D01*
G03Y519045I-183J81D01*
G37*
G36*
G01X1063298Y548581D02*
G02X1062998Y550000I3202J1418D01*
G02X1063298Y551419I3502J1D01*
G03Y551581I-183J81D01*
G02X1062998Y553000I3202J1418D01*
G02X1066500Y556502I3502J0D01*
G02X1067919Y556202I1J-3502D01*
G03X1068081I81J183D01*
G02X1069500Y556502I1418J-3202D01*
G02X1073002Y553000I0J-3502D01*
G02X1072702Y551581I-3502J-1D01*
G03Y551419I183J-81D01*
G02X1073002Y550000I-3202J-1418D01*
G02X1072702Y548581I-3502J-1D01*
G03Y548419I183J-81D01*
G02X1073002Y547000I-3202J-1418D01*
G02X1072702Y545581I-3502J-1D01*
G03Y545419I183J-81D01*
G02X1073002Y544000I-3202J-1418D01*
G02X1072702Y542581I-3502J-1D01*
G03Y542419I183J-81D01*
G02X1073002Y541000I-3202J-1418D01*
G02X1072702Y539581I-3502J-1D01*
G03Y539419I183J-81D01*
G02X1073002Y538000I-3202J-1418D01*
G02X1069500Y534498I-3502J0D01*
G02X1068081Y534798I-1J3502D01*
G03X1067919I-81J-183D01*
G02X1066500Y534498I-1418J3202D01*
G02X1062998Y538000I0J3502D01*
G02X1063298Y539419I3502J1D01*
G03Y539581I-183J81D01*
G02X1062998Y541000I3202J1418D01*
G02X1063298Y542419I3502J1D01*
G03Y542581I-183J81D01*
G02X1062998Y544000I3202J1418D01*
G02X1063298Y545419I3502J1D01*
G03Y545581I-183J81D01*
G02X1062998Y547000I3202J1418D01*
G02X1063298Y548419I3502J1D01*
G03Y548581I-183J81D01*
G37*
G36*
G01X159774Y229052D02*
G02X159348Y230728I3076J1674D01*
G02X162850Y234230I3502J0D01*
G02X164032Y234025I1J-3502D01*
G03X164168I68J188D01*
G02X165350Y234230I1181J-3297D01*
G02X168852Y230728I0J-3502D01*
G02X168426Y229052I-3502J-2D01*
G03Y228861I175J-95D01*
G02X168852Y227185I-3076J-1674D01*
G02X168426Y225509I-3502J-2D01*
G03Y225318I175J-95D01*
G02X168852Y223642I-3076J-1674D01*
G02X168425Y221966I-3503J0D01*
G03Y221774I176J-96D01*
G02X168852Y220098I-3076J-1676D01*
G02X166105Y216678I-3502J0D01*
G03X166073Y216297I43J-195D01*
G02X166132Y216273I-1290J-3256D01*
G03X166288I78J184D01*
G02X167660Y216552I1370J-3223D01*
G02X171162Y213050I0J-3502D01*
G02X170819Y211536I-3503J-2D01*
G03Y211364I180J-86D01*
G02X171162Y209850I-3160J-1512D01*
G02X167660Y206348I-3502J0D01*
G02X166288Y206627I-2J3502D01*
G03X166132I-78J-184D01*
G02X164760Y206348I-1370J3223D01*
G02X161258Y209850I0J3502D01*
G02X161601Y211364I3503J2D01*
G03Y211536I-180J86D01*
G02X161258Y213050I3160J1512D01*
G02X162709Y215889I3503J0D01*
G01X162761Y215926D01*
X162802Y216043D01*
X162671Y216526D01*
X162576Y216606D01*
X162513Y216612D01*
G02X159348Y220098I337J3486D01*
G02X159775Y221774I3503J0D01*
G03Y221966I-176J96D01*
G02X159348Y223642I3076J1676D01*
G02X159774Y225318I3502J2D01*
G03Y225509I-175J96D01*
G02X159348Y227185I3076J1674D01*
G02X159774Y228861I3502J2D01*
G03Y229052I-175J95D01*
G37*
G54D55*
X1092000Y82500D03*
X247441Y305975D03*
X404921D03*
X562402D03*
X719883D03*
X849000Y399000D03*
X1016614Y197767D03*
X1024340Y146600D03*
X1084325Y130197D03*
X154840Y244730D03*
X1067866Y507629D03*
X1060984Y418742D03*
X1061600Y513742D03*
X1067730Y460352D03*
X1061600Y466242D03*
X1086500Y403500D03*
X1061600Y323742D03*
X1086500Y356000D03*
X1067531Y412942D03*
X1158200Y137700D03*
X1067679Y317942D03*
X1067707Y365442D03*
X1061600Y276242D03*
X1067701Y270442D03*
X1152781Y165719D03*
X1152500Y186500D03*
X1080418Y373600D03*
G54D59*
X1226024Y286929D03*
G54D60*
X48780Y329724D03*
G54D57*
X268000Y240000D03*
X312500D03*
X357000D03*
X428500D03*
X472500D03*
X516500D03*
X578500D03*
X622500D03*
X666500D03*
X735981D03*
X779981D03*
X823981D03*
G54D56*
X165539Y539000D03*
X213539D03*
X261539D03*
X323019D03*
X371019D03*
X419019D03*
X480500D03*
X528500D03*
X576500D03*
X637981D03*
X685981D03*
X733981D03*
G54D58*
X253819Y477204D03*
X411299D03*
X568780D03*
X726261D03*
G54D52*
X19922Y367716D03*
Y214173D03*
G54D53*
X964460Y16950D03*
X877510Y558620D03*
X175000Y100500D03*
X1271654Y636929D03*
X619685D03*
G54D54*
X108858Y99724D03*
Y482205D03*
G54D51*
X665059Y149408D03*
X980059D03*
X529252Y129685D03*
X249252D03*
X1226024Y174429D03*
%LPC*%
G75*
G36*
G01X1102061Y377400D02*
X1173385D01*
G02X1173527Y377341I0J-200D01*
G01X1178112Y372756D01*
G02X1178171Y372614I-141J-142D01*
G01Y338657D01*
G02X1178140Y338551I-200J1D01*
G03X1177909Y337750I1271J-800D01*
G03X1178140Y336949I1502J-1D01*
G02X1178171Y336843I-169J-107D01*
G01Y335157D01*
G02X1178140Y335051I-200J1D01*
G03X1177909Y334250I1271J-800D01*
G03X1178140Y333449I1502J-1D01*
G02X1178171Y333343I-169J-107D01*
G01Y331657D01*
G02X1178140Y331551I-200J1D01*
G03X1177909Y330750I1271J-800D01*
G03X1178140Y329949I1502J-1D01*
G02X1178171Y329843I-169J-107D01*
G01Y328157D01*
G02X1178140Y328051I-200J1D01*
G03X1177909Y327250I1271J-800D01*
G03X1178140Y326449I1502J-1D01*
G02X1178171Y326343I-169J-107D01*
G01Y310199D01*
X1178168Y310183D01*
G03X1178149Y309942I1483J-238D01*
G03X1178168Y309701I1502J-3D01*
G01X1178171Y309685D01*
Y306199D01*
X1178168Y306183D01*
G03X1178149Y305942I1483J-238D01*
G03X1178168Y305701I1502J-3D01*
G01X1178171Y305685D01*
Y240893D01*
G02X1178112Y240751I-200J0D01*
G01X1174527Y237166D01*
G02X1174385Y237107I-142J141D01*
G01X1101890D01*
G02X1101748Y237166I0J200D01*
G01X1097334Y241580D01*
G02X1097275Y241722I141J142D01*
G01Y372614D01*
G02X1097334Y372756I200J0D01*
G01X1101919Y377341D01*
G02X1102061Y377400I142J-141D01*
G37*
G36*
G01X1101564Y521466D02*
X1174418D01*
G02X1174560Y521407I0J-200D01*
G01X1178112Y517855D01*
G02X1178171Y517713I-141J-142D01*
G01Y480974D01*
X1178161Y480931D01*
X1178151Y480910D01*
G03X1177998Y480250I1349J-660D01*
G03X1178151Y479590I1502J0D01*
G01X1178161Y479569D01*
X1178171Y479526D01*
Y477474D01*
X1178161Y477431D01*
X1178151Y477410D01*
G03X1177998Y476750I1349J-660D01*
G03X1178151Y476090I1502J0D01*
G01X1178161Y476069D01*
X1178171Y476026D01*
Y473974D01*
X1178161Y473931D01*
X1178151Y473910D01*
G03X1177998Y473250I1349J-660D01*
G03X1178151Y472590I1502J0D01*
G01X1178161Y472569D01*
X1178171Y472526D01*
Y470474D01*
X1178161Y470431D01*
X1178151Y470410D01*
G03X1177998Y469750I1349J-660D01*
G03X1178151Y469090I1502J0D01*
G01X1178161Y469069D01*
X1178171Y469026D01*
Y386186D01*
G02X1178112Y386044I-200J0D01*
G01X1173527Y381459D01*
G02X1173385Y381400I-142J141D01*
G01X1102061D01*
G02X1101919Y381459I0J200D01*
G01X1097334Y386044D01*
G02X1097275Y386186I141J142D01*
G01Y517177D01*
G02X1097334Y517319I200J0D01*
G01X1101422Y521407D01*
G02X1101564Y521466I142J-141D01*
G37*
G36*
G01X1205314Y291525D02*
X1184505D01*
G02X1184363Y291584I0J200D01*
G01X1182230Y293717D01*
G02X1182171Y293859I141J142D01*
G01Y348245D01*
G02X1182208Y348361I200J0D01*
G03Y350107I-1222J873D01*
G02X1182171Y350223I163J116D01*
G01Y474987D01*
G02X1182230Y475129I200J0D01*
G01X1186142Y479041D01*
G02X1186284Y479100I142J-141D01*
G01X1257489D01*
G02X1257631Y479041I0J-200D01*
G01X1261441Y475231D01*
G02X1261500Y475089I-141J-142D01*
G01Y303511D01*
G02X1261441Y303369I-200J0D01*
G01X1258631Y300559D01*
G02X1258489Y300500I-142J141D01*
G01X1215200D01*
G03X1213786Y299914I0J-1999D01*
G01X1205456Y291584D01*
G02X1205314Y291525I-142J141D01*
G37*
%LPD*%
G75*
G54D61*
X1226024Y399429D03*
G54D20*
X63436Y353962D03*
X108600Y258560D03*
X111600D03*
X108600Y261560D03*
X111600D03*
X108600Y255560D03*
X111600D03*
X123000Y414500D03*
X119500D03*
Y411500D03*
X123000D03*
X119500Y408500D03*
X123000D03*
X119500Y417500D03*
X123000D03*
X119500Y420500D03*
X123000D03*
X115700Y420600D03*
Y417600D03*
Y408600D03*
Y411600D03*
Y414600D03*
X123000Y426600D03*
X119500D03*
X123000Y423600D03*
X119500D03*
X115700Y423700D03*
Y426700D03*
X150634Y219063D03*
X154840Y244730D03*
X155034Y228063D03*
Y224563D03*
X152334Y223063D03*
Y226563D03*
Y230063D03*
X155034Y231563D03*
X182260Y197050D03*
X179460D03*
X176560D03*
X174660Y205850D03*
Y202650D03*
X167660Y213050D03*
X164760D03*
X167660Y209850D03*
X164760D03*
X183900Y216830D03*
X178265Y213443D03*
X175976Y218775D03*
X165840Y247805D03*
X169840D03*
X166068Y238749D03*
X173869Y228168D03*
X175481Y225183D03*
X160017Y237764D03*
X161400Y323200D03*
X157000Y414500D03*
X160500D03*
Y417500D03*
X157000D03*
X160500Y420500D03*
X157000D03*
X160500Y411500D03*
X157000D03*
X160500Y408500D03*
X157000D03*
X164000Y414600D03*
Y417600D03*
Y420600D03*
Y411600D03*
Y408600D03*
X160300Y423600D03*
X156800D03*
X160300Y426600D03*
X156800D03*
X163800Y426700D03*
Y423700D03*
X168939Y498000D03*
X171939D03*
Y518000D03*
X168939D03*
X194160Y205200D03*
Y208200D03*
X200160Y205200D03*
Y208200D03*
X197160Y205200D03*
Y208200D03*
X185260Y205350D03*
Y208350D03*
X203575Y297500D03*
X212925Y315500D03*
X218500Y309500D03*
X226975D03*
X235975D03*
X230425Y313605D03*
X221425Y313000D03*
X216939Y498000D03*
X219939D03*
Y518000D03*
X216939D03*
X247441Y305975D03*
X264939Y498000D03*
X267939D03*
Y518000D03*
X264939D03*
X283000Y203500D03*
Y198500D03*
Y196000D03*
Y206000D03*
X285219Y279078D03*
X281219D03*
X277219D03*
X285219Y275078D03*
X281219D03*
X277219D03*
X285219Y271078D03*
X281219D03*
X277219D03*
Y283078D03*
X281219D03*
X285219D03*
X326000Y203500D03*
Y198500D03*
Y196000D03*
Y206000D03*
X304500Y203500D03*
Y198500D03*
Y196000D03*
Y206000D03*
X326419Y498000D03*
X329419D03*
Y518000D03*
X326419D03*
X347500Y203500D03*
Y198500D03*
Y196000D03*
Y206000D03*
X361000Y305975D03*
X390500Y203500D03*
Y198500D03*
Y196000D03*
Y206000D03*
X369000Y203500D03*
Y198500D03*
Y196000D03*
Y206000D03*
X375500Y309500D03*
X383975D03*
X382963Y316400D03*
Y313750D03*
X374419Y498000D03*
X377419D03*
Y518000D03*
X374419D03*
X412000Y203500D03*
Y198500D03*
Y196000D03*
Y206000D03*
X404921Y305975D03*
X392975Y309500D03*
X442499Y279186D03*
X438499D03*
X434499D03*
X442499Y275186D03*
X438499D03*
X434499D03*
X442499Y271186D03*
X438499D03*
X434499D03*
Y283186D03*
X438499D03*
X442499D03*
X422419Y498000D03*
X425419D03*
Y518000D03*
X422419D03*
X483900Y498000D03*
X486900D03*
Y518000D03*
X483900D03*
X518575Y295500D03*
X533475Y310500D03*
X539619Y316400D03*
Y313400D03*
X531900Y498000D03*
X534900D03*
Y518000D03*
X531900D03*
X562402Y305975D03*
X542475Y310500D03*
X551475D03*
X562000Y442000D03*
X564500D03*
X590500Y203000D03*
Y198000D03*
Y195500D03*
Y205500D03*
X582900Y518000D03*
Y498000D03*
X579900D03*
Y518000D03*
X612000Y203000D03*
Y198000D03*
Y195500D03*
Y205500D03*
X640900Y42300D03*
X647999Y33000D03*
X638200Y44000D03*
Y46500D03*
X641100Y48100D03*
X655000Y203000D03*
Y198000D03*
Y195500D03*
Y205500D03*
X633500Y203000D03*
Y198000D03*
Y195500D03*
Y205500D03*
X644381Y518000D03*
Y498000D03*
X641381D03*
Y518000D03*
X690075Y39500D03*
X676500Y195500D03*
Y198000D03*
Y203000D03*
Y205500D03*
X676075Y299600D03*
X680400Y310500D03*
X703740Y41000D03*
X707000Y32000D03*
X694425Y29500D03*
X703740Y54118D03*
X697990Y195500D03*
Y198000D03*
Y203000D03*
Y205500D03*
X716100Y255987D03*
X700040Y258960D03*
X694406Y295500D03*
X690956Y310500D03*
X699956D03*
X708956D03*
X697100Y313400D03*
X704400Y358600D03*
X702200Y356000D03*
X697900Y352500D03*
X707750Y358750D03*
X692381Y518000D03*
Y498000D03*
X689381D03*
Y518000D03*
X747160Y30000D03*
Y38500D03*
Y64000D03*
Y47000D03*
Y55500D03*
X719490Y195500D03*
Y198000D03*
Y203000D03*
Y205500D03*
X719883Y305975D03*
X724000Y294500D03*
X742500Y328500D03*
Y324500D03*
Y334500D03*
X735075Y326000D03*
Y336000D03*
X731925D03*
X732000Y326000D03*
X742000Y341500D03*
X742500Y347700D03*
Y353200D03*
X740381Y518000D03*
Y498000D03*
X737381D03*
Y518000D03*
X750300Y27200D03*
X752560Y30100D03*
X749760D03*
X752560Y38600D03*
X749760D03*
X752560Y64100D03*
X749760D03*
X752560Y47100D03*
X749760D03*
X752560Y55600D03*
X749760D03*
X754000Y353500D03*
Y356957D03*
X748075Y366500D03*
X803900Y279425D03*
X803500Y259525D03*
X784855Y265184D03*
X790000Y259612D03*
X794900Y265979D03*
X806000Y265075D03*
X806500Y285500D03*
X800575Y338000D03*
X779100Y326820D03*
X798400Y323900D03*
X786500Y316700D03*
X793800Y323880D03*
X781500Y362700D03*
X803000Y357000D03*
Y346500D03*
X802975Y362000D03*
X792000Y358000D03*
X805323Y408150D03*
Y405150D03*
X799323D03*
Y408150D03*
X802323Y405150D03*
Y408150D03*
X796600Y408097D03*
Y405097D03*
X802323Y416916D03*
X799323D03*
X805323D03*
X802323Y413916D03*
X799323D03*
X805323D03*
Y411150D03*
X799323D03*
X802323D03*
X796600Y411097D03*
Y413863D03*
Y416863D03*
X799655Y474684D03*
Y480503D03*
Y477684D03*
X802655Y474684D03*
Y480503D03*
Y477684D03*
X805655Y474684D03*
Y480503D03*
Y477684D03*
X802655Y483503D03*
X805709Y486332D03*
X805655Y483503D03*
X796655Y474684D03*
Y480503D03*
Y477684D03*
X796709Y486332D03*
X796655Y483503D03*
X799709Y486332D03*
X799655Y483503D03*
X802709Y486332D03*
X831000Y270500D03*
X808500Y276075D03*
X836000Y270500D03*
X826000Y270525D03*
X833500Y268575D03*
X821000Y270525D03*
X816000D03*
X827602Y283500D03*
X836500Y302500D03*
X814500Y293000D03*
X811500Y329000D03*
X815500D03*
X823500D03*
X819500Y318500D03*
X808425Y334000D03*
X831750Y318250D03*
X829500Y354925D03*
X827000Y360475D03*
X811575Y344000D03*
X827000Y352500D03*
X808425Y344000D03*
X811323Y405150D03*
Y408150D03*
X808323D03*
Y405150D03*
Y416916D03*
X811323D03*
X808323Y413916D03*
X811323D03*
Y411150D03*
X808323D03*
X817153Y408096D03*
Y405096D03*
X814323Y405150D03*
Y408150D03*
Y416916D03*
X817153Y416862D03*
X814323Y413916D03*
X817153Y413862D03*
Y411096D03*
X814323Y411150D03*
X817709Y486332D03*
X817655Y483503D03*
X808655Y474684D03*
Y480503D03*
Y477684D03*
X811655Y474684D03*
Y480503D03*
Y477684D03*
X814655D03*
Y480503D03*
Y474684D03*
X808709Y486332D03*
X808655Y483503D03*
X811709Y486332D03*
X811655Y483503D03*
X814655D03*
X814709Y486332D03*
X817655Y474684D03*
Y480503D03*
Y477684D03*
X863600Y208900D03*
X841000Y270500D03*
X846000Y270525D03*
X851000D03*
X856000D03*
X843500Y268575D03*
X853500D03*
X850750Y250750D03*
X853000Y303500D03*
X861600Y304600D03*
X845000Y303000D03*
X848500Y335800D03*
X839692Y329592D03*
X854825Y330925D03*
X850500Y356925D03*
X843843Y354342D03*
X864500Y358500D03*
X849000Y399000D03*
X850390Y385878D03*
X847390D03*
X859253D03*
X856253D03*
X865542Y385771D03*
X859342Y413916D03*
X856342D03*
X865342D03*
X862342D03*
Y411150D03*
X865342D03*
X856342D03*
X859342D03*
X853619Y411097D03*
Y413863D03*
Y416863D03*
X862342Y408150D03*
Y405150D03*
X865342Y408150D03*
Y405150D03*
X856342D03*
Y408150D03*
X859342Y405150D03*
Y408150D03*
X853619Y408097D03*
Y405097D03*
X859342Y416916D03*
X856342D03*
X865342D03*
X862342D03*
X856257Y474684D03*
Y480503D03*
Y477684D03*
X859257Y474684D03*
Y480503D03*
Y477684D03*
X862257Y474684D03*
Y480503D03*
Y477684D03*
X859257Y483503D03*
X862311Y486332D03*
X862257Y483503D03*
X853257Y474684D03*
Y480503D03*
Y477684D03*
X853311Y486332D03*
X853257Y483503D03*
X856311Y486332D03*
X856257Y483503D03*
X859311Y486332D03*
X865311D03*
X865257Y483503D03*
Y474684D03*
Y480503D03*
Y477684D03*
X854082Y505410D03*
X848263D03*
X851082D03*
X854082Y508410D03*
X848263D03*
X851082D03*
X854082Y511410D03*
X848263D03*
X851082D03*
X854082Y514410D03*
X848263D03*
X851082D03*
X845263Y508410D03*
X842434Y511464D03*
X845263Y511410D03*
X842434Y514464D03*
X845263Y514410D03*
X854082Y502410D03*
X848263D03*
X851082D03*
X842434Y502464D03*
X845263Y502410D03*
X842434Y505464D03*
X845263Y505410D03*
X842434Y508464D03*
Y523464D03*
X845263Y523410D03*
X854082Y517410D03*
X848263D03*
X851082D03*
Y520410D03*
X848263D03*
X854082D03*
X842434Y517464D03*
X845263Y517410D03*
Y520410D03*
X842434Y520464D03*
X854082Y523410D03*
X848263D03*
X851082D03*
X868000Y271500D03*
X867000Y291260D03*
X870000Y304525D03*
X875000D03*
X880000D03*
X888000Y283475D03*
X870000Y312788D03*
X880000Y312855D03*
X875000Y347273D03*
X874000Y358475D03*
X885500Y352925D03*
X869000Y360500D03*
X893091Y385771D03*
X874405D03*
X877405D03*
X868542D03*
X884228D03*
X887228D03*
X868342Y416916D03*
X871342D03*
X868342Y413916D03*
X871342D03*
Y411150D03*
X868342D03*
X874172Y408096D03*
Y405096D03*
Y416862D03*
Y413862D03*
Y411096D03*
X871342Y405150D03*
Y408150D03*
X868342Y405150D03*
Y408150D03*
X868311Y486332D03*
X868257Y483503D03*
Y477684D03*
Y480503D03*
Y474684D03*
X871311Y486332D03*
X874311D03*
X874257Y477684D03*
Y480503D03*
Y474684D03*
X871257Y483503D03*
Y474684D03*
Y480503D03*
Y477684D03*
X874257Y483503D03*
X909000Y283475D03*
X904500Y292000D03*
X915000Y322425D03*
X912000Y332425D03*
X905941Y320366D03*
X903500Y327975D03*
X916260Y355000D03*
X910992Y361075D03*
X920000Y355525D03*
X923740Y345500D03*
X896091Y385771D03*
X912525Y385877D03*
X906662D03*
X903662D03*
X922454Y385771D03*
X915525Y385877D03*
X911776Y507184D03*
Y510184D03*
Y501184D03*
Y504184D03*
X923595Y498461D03*
X920595D03*
X920542Y504184D03*
X923542D03*
X920542Y501184D03*
X923542D03*
Y510184D03*
X920542D03*
X923542Y507184D03*
X920542D03*
Y513184D03*
X923542D03*
X911829Y498461D03*
X914829D03*
X917595D03*
X917542Y504184D03*
Y501184D03*
Y510184D03*
Y507184D03*
Y513184D03*
X914776D03*
Y507184D03*
Y510184D03*
Y501184D03*
Y504184D03*
X911776Y513184D03*
X920542Y516184D03*
X923542D03*
X917542D03*
X914776D03*
X911776D03*
X917596Y519014D03*
X914830D03*
X911830D03*
X923596D03*
X920596D03*
X940575Y304000D03*
X926000Y283475D03*
X937516Y300075D03*
X947000Y302475D03*
X940000Y283800D03*
X930500Y315460D03*
X943172Y310885D03*
X943171Y315385D03*
X935516Y361075D03*
X927000Y357925D03*
X943885Y352385D03*
X933357Y344843D03*
X933196Y353360D03*
X925454Y385771D03*
X944247Y385877D03*
X941247D03*
X931317Y385771D03*
X934317D03*
X950110Y385877D03*
X953110D03*
X1022575Y100925D03*
Y115500D03*
X1034500Y145000D03*
X1037000Y146300D03*
X1037500Y142000D03*
X1036500Y153500D03*
X1043936Y145745D03*
X1019040Y157310D03*
X1019030Y160330D03*
X1022168Y155877D03*
Y161783D03*
X1017909Y151424D03*
X1017837Y154280D03*
X1024340Y146600D03*
X1016614Y187267D03*
Y190267D03*
X1036500Y172000D03*
Y163000D03*
X1039016Y189075D03*
Y183027D03*
X1039538Y179208D03*
X1039016Y185925D03*
X1022000Y171200D03*
X1019700Y166600D03*
X1016614Y197767D03*
X1057525Y130500D03*
X1049356Y143900D03*
X1047159Y141487D03*
X1054500Y148500D03*
X1048000Y153500D03*
X1057525Y134000D03*
Y138600D03*
X1073154Y140800D03*
X1057500Y155877D03*
X1070715Y146500D03*
X1063500Y159814D03*
X1048000Y172000D03*
Y163000D03*
X1060500Y164500D03*
X1062500Y191500D03*
X1067000D03*
X1070000D03*
X1058000D03*
X1053830Y191670D03*
X1060000Y249000D03*
X1063000D03*
X1066000D03*
Y246000D03*
X1063000D03*
X1060000D03*
X1066000Y243000D03*
X1063000D03*
X1060000D03*
X1069000Y246000D03*
Y243000D03*
X1072000Y246000D03*
Y243000D03*
X1060000Y252000D03*
X1063000D03*
X1066000D03*
Y258000D03*
X1063000D03*
X1060000D03*
X1066000Y255000D03*
X1063000D03*
X1060000D03*
X1069000Y258000D03*
Y255000D03*
X1072000Y258000D03*
Y255000D03*
X1067701Y270442D03*
X1061600Y276242D03*
X1060000Y296500D03*
X1063000D03*
X1066000D03*
Y293500D03*
X1063000D03*
X1060000D03*
X1069000D03*
X1060000Y299500D03*
X1063000D03*
X1066000D03*
Y305500D03*
X1063000D03*
X1060000D03*
X1066000Y302500D03*
X1063000D03*
X1060000D03*
X1069000Y305500D03*
Y302500D03*
X1066000Y290500D03*
X1063000D03*
X1060000D03*
X1069000D03*
X1072000Y293500D03*
Y305500D03*
Y302500D03*
Y290500D03*
X1066000Y338000D03*
X1063000D03*
X1060000D03*
X1069000D03*
X1072000D03*
X1067679Y317942D03*
X1061600Y323742D03*
X1060000Y344000D03*
X1063000D03*
X1066000D03*
X1060000Y347000D03*
X1063000D03*
X1066000D03*
Y341000D03*
X1063000D03*
X1060000D03*
X1066000Y353000D03*
X1063000D03*
X1060000D03*
X1066000Y350000D03*
X1063000D03*
X1060000D03*
X1069000Y353000D03*
Y350000D03*
Y341000D03*
X1072000Y353000D03*
Y350000D03*
Y341000D03*
X1067707Y365442D03*
X1061600Y359642D03*
X1066000Y397500D03*
X1063000D03*
X1060000D03*
X1069000D03*
X1060000Y391500D03*
X1063000D03*
X1066000D03*
X1060000Y394500D03*
X1063000D03*
X1066000D03*
Y388500D03*
X1063000D03*
X1060000D03*
X1066000Y385500D03*
X1063000D03*
X1060000D03*
X1069000Y388500D03*
Y385500D03*
X1072000Y397500D03*
Y388500D03*
Y385500D03*
X1066000Y400500D03*
X1063000D03*
X1060000D03*
X1069000D03*
X1072000D03*
X1067531Y412942D03*
X1060984Y418742D03*
X1066000Y433000D03*
X1063000D03*
X1060000D03*
X1069000D03*
X1060000Y439000D03*
X1063000D03*
X1066000D03*
X1060000Y442000D03*
X1063000D03*
X1066000D03*
Y436000D03*
X1063000D03*
X1060000D03*
X1069000D03*
X1072000Y433000D03*
Y436000D03*
X1066000Y448000D03*
X1063000D03*
X1060000D03*
X1066000Y445000D03*
X1063000D03*
X1060000D03*
X1069000Y448000D03*
Y445000D03*
X1072000Y448000D03*
Y445000D03*
X1069000Y480500D03*
Y483500D03*
X1060000Y480500D03*
X1063000D03*
X1066000D03*
X1060000Y483500D03*
X1063000D03*
X1066000D03*
Y486500D03*
X1063000D03*
X1060000D03*
X1072000Y480500D03*
Y483500D03*
X1067730Y460352D03*
X1061600Y466242D03*
X1069000Y492500D03*
Y495500D03*
X1060000Y492500D03*
X1063000D03*
X1066000D03*
X1060000Y495500D03*
X1063000D03*
X1066000D03*
Y489500D03*
X1063000D03*
X1060000D03*
X1072000Y492500D03*
Y495500D03*
X1067866Y507629D03*
X1061600Y513742D03*
X1066500Y538000D03*
Y541000D03*
X1069500D03*
X1066500Y544000D03*
X1069500D03*
Y538000D03*
Y547000D03*
Y550000D03*
X1066500Y547000D03*
Y550000D03*
Y553000D03*
X1069500D03*
X1092000Y82500D03*
X1087000Y100000D03*
X1073200Y90900D03*
X1077200D03*
X1084325Y130197D03*
X1094493Y151856D03*
X1073154Y137800D03*
X1082000Y143600D03*
X1092000Y159500D03*
X1094500Y143144D03*
X1084401Y159260D03*
X1094024Y179500D03*
X1085000Y184575D03*
X1079500D03*
X1085525Y167500D03*
Y171000D03*
Y174500D03*
Y164000D03*
X1087500Y198000D03*
Y201000D03*
X1097500Y203700D03*
X1100000D03*
X1073500Y191500D03*
X1086500Y356000D03*
X1080418Y373600D03*
X1086500Y403500D03*
X1074316Y406925D03*
X1123000Y120816D03*
X1126000D03*
X1131500D03*
X1115800Y126600D03*
X1130125Y135940D03*
X1126075Y135973D03*
X1121238Y144500D03*
X1108500Y136500D03*
X1104500Y136524D03*
X1120524Y138457D03*
X1129000Y157000D03*
X1120200D03*
X1115425Y138925D03*
X1119000Y189500D03*
X1111100Y163749D03*
X1123500Y187000D03*
X1108000Y172000D03*
X1113368Y171619D03*
X1110800Y170000D03*
X1113129Y165719D03*
X1114500Y188700D03*
X1120200Y176500D03*
Y166500D03*
X1129000D03*
Y176500D03*
X1108821Y166800D03*
X1125918Y195418D03*
X1129068Y195500D03*
X1133000Y198000D03*
X1117206Y231741D03*
X1117290Y224241D03*
X1106189D03*
X1106106Y231741D03*
X1134500Y120816D03*
X1158200Y137700D03*
X1136300Y161100D03*
X1140000D03*
X1160200Y175982D03*
X1152781Y165719D03*
X1136300Y172300D03*
X1140000D03*
X1140336Y183560D03*
X1143490D03*
X1152500Y186500D03*
X1158000Y179000D03*
X1162700Y175959D03*
X1183021Y165952D03*
X1185521D03*
X1188600Y166000D03*
X1188618Y162782D03*
X1185521Y162952D03*
X1183021D03*
X1180521D03*
Y165952D03*
X1177521D03*
Y162952D03*
X1167600Y184500D03*
Y180500D03*
X1174500Y214000D03*
Y211000D03*
Y208000D03*
Y205000D03*
X1171500D03*
Y208000D03*
Y211000D03*
Y214000D03*
X1179651Y305942D03*
Y309942D03*
X1165070Y328750D03*
X1193411D03*
X1179411Y334250D03*
Y337750D03*
Y330750D03*
Y327250D03*
X1180986Y349234D03*
X1177836D03*
X1179877Y452442D03*
Y448442D03*
X1165190Y471250D03*
X1179500Y476750D03*
Y480250D03*
Y469750D03*
Y473250D03*
X1181075Y491734D03*
X1177925D03*
X1193840Y471250D03*
G54D12*
X72836Y47244D03*
Y535433D03*
X466536Y47244D03*
X860237D03*
X943225Y228000D03*
X985225Y542500D03*
G54D35*
X268000Y240000D03*
X312500D03*
X357000D03*
X428500D03*
X472500D03*
X516500D03*
X578500D03*
X622500D03*
X666500D03*
X735981D03*
X779981D03*
X823981D03*
G54D16*
X38780Y272598D03*
Y279291D03*
Y292598D03*
Y299291D03*
X48780Y272598D03*
Y279291D03*
Y292598D03*
Y299291D03*
G54D25*
X165350Y220098D03*
X162850D03*
Y227185D03*
Y230728D03*
X165350Y223642D03*
Y227185D03*
Y230728D03*
X162850Y223642D03*
G54D28*
X165539Y539000D03*
X213539D03*
X261539D03*
X323019D03*
X371019D03*
X419019D03*
X480500D03*
X528500D03*
X576500D03*
X637981D03*
X685981D03*
X733981D03*
G54D17*
X33780Y334724D03*
Y314724D03*
X38780Y319724D03*
Y329724D03*
Y339724D03*
X33780Y344724D03*
X38780Y349724D03*
X48780Y319724D03*
Y329724D03*
Y339724D03*
X43780Y314724D03*
Y324724D03*
Y334724D03*
X48780Y349724D03*
X43780Y344724D03*
G54D23*
X155140Y240230D03*
X172934Y219110D03*
X172712Y222263D03*
X183815Y220903D03*
X808500Y272925D03*
X831000Y260500D03*
X836000D03*
X825941Y339560D03*
X835610Y355590D03*
X841000Y260525D03*
X865000Y313200D03*
X878000Y358475D03*
X883000Y358500D03*
X1070400Y123200D03*
X1067600D03*
X1111452Y544000D03*
Y541000D03*
X1114452Y544000D03*
Y541000D03*
Y538000D03*
X1111452D03*
X1120669Y544000D03*
Y541000D03*
X1123669Y544000D03*
Y541000D03*
Y538000D03*
X1120669D03*
X1114452Y553000D03*
X1111452D03*
X1114452Y550000D03*
X1111452D03*
X1114452Y547000D03*
X1111452D03*
X1123669Y553000D03*
X1120669D03*
X1123669Y550000D03*
X1120669D03*
X1123669Y547000D03*
X1120669D03*
G54D27*
X180539Y498000D03*
X183539D03*
X228539D03*
X231539D03*
X276539D03*
X279539D03*
X338019D03*
X341019D03*
X386019D03*
X389019D03*
X434019D03*
X437019D03*
X498500D03*
X495500D03*
X546500D03*
X543500D03*
X594500D03*
X591500D03*
X655981D03*
X652981D03*
X703981D03*
X700981D03*
X748981D03*
X751981D03*
X826000Y260525D03*
X848075Y306500D03*
X912500Y327975D03*
X1159710Y306037D03*
X1156710D03*
X1159710Y303037D03*
X1156710D03*
X1159710Y300037D03*
X1156710D03*
X1159710Y297037D03*
X1156710D03*
Y294037D03*
X1159710D03*
Y309037D03*
X1156710D03*
X1159710Y312037D03*
X1156710D03*
X1159710Y321037D03*
X1156710D03*
X1159710Y318037D03*
X1156710D03*
X1159710Y315037D03*
X1156710D03*
X1159799Y448537D03*
X1156799D03*
X1159799Y445537D03*
X1156799D03*
X1159799Y442537D03*
X1156799D03*
X1159799Y439537D03*
X1156799D03*
Y436537D03*
X1159799D03*
Y454537D03*
X1156799D03*
X1159799Y451537D03*
X1156799D03*
X1159799Y457537D03*
X1156799D03*
X1159799Y463537D03*
X1156799D03*
X1159799Y460537D03*
X1156799D03*
X1162710Y306037D03*
Y303037D03*
Y300037D03*
Y297037D03*
Y294037D03*
Y309037D03*
Y312037D03*
Y321037D03*
Y318037D03*
Y315037D03*
X1162799Y448537D03*
Y445537D03*
Y442537D03*
Y439537D03*
Y436537D03*
Y454537D03*
Y451537D03*
Y457537D03*
Y463537D03*
Y460537D03*
G54D30*
X208071Y267204D03*
X200197D03*
X215945D03*
X231693D03*
X223819D03*
X239567D03*
X247441D03*
X357677D03*
X365551D03*
X373425D03*
X389173D03*
X381299D03*
X404921D03*
X397047D03*
X523032D03*
X515158D03*
X530906D03*
X538780D03*
X546654D03*
X562402D03*
X554528D03*
X680513D03*
X672639D03*
X688387D03*
X704135D03*
X696261D03*
X712009D03*
X719883D03*
G54D33*
X223819Y477204D03*
X253819D03*
X381299D03*
X411299D03*
X538780D03*
X568780D03*
X696261D03*
X726261D03*
G54D38*
X411752Y129685D03*
X401752D03*
X411752Y139685D03*
Y149685D03*
Y159685D03*
X401752Y139685D03*
Y149685D03*
Y159685D03*
X446752Y129685D03*
X436752D03*
X446752Y139685D03*
Y149685D03*
Y159685D03*
X436752Y139685D03*
Y149685D03*
Y159685D03*
X481752Y129685D03*
X471752D03*
X481752Y139685D03*
Y149685D03*
Y159685D03*
X471752Y139685D03*
Y149685D03*
Y159685D03*
X712559Y129408D03*
Y119408D03*
Y149408D03*
Y139408D03*
X722559Y129408D03*
Y119408D03*
X747559Y129408D03*
Y119408D03*
X722559Y149408D03*
Y139408D03*
X747559Y149408D03*
Y139408D03*
X757559Y129408D03*
Y119408D03*
Y149408D03*
Y139408D03*
X782559Y129408D03*
Y119408D03*
X792559Y129408D03*
Y119408D03*
X782559Y149408D03*
Y139408D03*
X792559Y149408D03*
Y139408D03*
X812559Y119408D03*
Y129408D03*
X822559Y119408D03*
Y129408D03*
X832559Y119408D03*
Y129408D03*
X812559Y149408D03*
X822559Y139408D03*
Y149408D03*
X832559Y139408D03*
Y149408D03*
X1226024Y286929D03*
X1236024D03*
X1246024D03*
X1256024D03*
G54D43*
X1011000Y98000D03*
Y118000D03*
X1161000Y90400D03*
X1151000D03*
X1171000D03*
G54D40*
X766498Y602542D03*
X766604Y630687D03*
X766498Y612542D03*
X766604Y640687D03*
X1082833Y602542D03*
Y612542D03*
Y630687D03*
Y640687D03*
G54D37*
X296752Y129685D03*
Y139685D03*
Y149685D03*
Y159685D03*
X331752Y129685D03*
X306752D03*
X331752Y139685D03*
Y149685D03*
Y159685D03*
X306752Y139685D03*
Y149685D03*
Y159685D03*
X341752Y129685D03*
Y139685D03*
Y149685D03*
Y159685D03*
X376752Y129685D03*
X366752D03*
X376752Y139685D03*
Y149685D03*
Y159685D03*
X366752Y139685D03*
Y149685D03*
Y159685D03*
X1226024Y221929D03*
X1236024D03*
X1246024D03*
X1226024Y231929D03*
X1236024D03*
X1246024D03*
X1226024Y256929D03*
X1236024D03*
X1246024D03*
X1226024Y266929D03*
X1236024D03*
X1246024D03*
X1226024Y306929D03*
X1236024D03*
X1246024D03*
X1226024Y316929D03*
X1236024D03*
X1246024D03*
X1226024Y341929D03*
X1236024D03*
X1246024D03*
X1226024Y351929D03*
X1236024D03*
X1246024D03*
X1256024Y221929D03*
Y231929D03*
Y256929D03*
Y266929D03*
Y306929D03*
Y316929D03*
Y341929D03*
Y351929D03*
G54D26*
X178819Y277204D03*
X193819D03*
X336299D03*
X351299D03*
X493780D03*
X508780D03*
X651261D03*
X666261D03*
G54D44*
X1011000Y108000D03*
G54D29*
X185224Y539000D03*
X233224D03*
X281224D03*
X342704D03*
X390704D03*
X438704D03*
X500185D03*
X548185D03*
X596185D03*
X657666D03*
X705666D03*
X753666D03*
G54D46*
X1096017Y635687D03*
G54D45*
Y607542D03*
G54D36*
X253819Y277204D03*
X268819D03*
X411299D03*
X426299D03*
X568780D03*
X583780D03*
X726261D03*
X741261D03*
G54D13*
X118111Y47244D03*
Y535433D03*
X511811Y47244D03*
X905512D03*
X988500Y228000D03*
X1030500Y542500D03*
G54D11*
X19685Y-614173D03*
Y636929D03*
X619685D03*
X1271654Y-614173D03*
Y636929D03*
G54D14*
X19922Y214173D03*
Y367716D03*
G54D24*
X175000Y100500D03*
X877510Y558620D03*
X964460Y16950D03*
G54D21*
X82795Y99724D03*
Y482205D03*
G54D32*
X249252Y129685D03*
X529252D03*
X665059Y149408D03*
X980059D03*
X1226024Y174429D03*
Y399429D03*
G54D19*
X60630Y99724D03*
Y482205D03*
X108858Y99724D03*
Y482205D03*
G54D22*
X153480Y213350D03*
X941035Y344474D03*
X1097100Y35582D03*
Y38582D03*
X1099600D03*
Y35582D03*
X1102100D03*
Y38582D03*
X1096961Y18126D03*
Y21126D03*
X1099461D03*
Y18126D03*
X1101961D03*
Y21126D03*
X1097101Y53737D03*
Y56737D03*
X1099601D03*
Y53737D03*
X1102101D03*
Y56737D03*
X1125170Y35582D03*
Y38582D03*
X1127670D03*
Y35582D03*
X1130170D03*
Y38582D03*
X1104600Y35582D03*
Y38582D03*
X1107100Y35582D03*
Y38582D03*
X1104461Y18126D03*
Y21126D03*
X1106961Y18126D03*
Y21126D03*
X1130031D03*
Y18126D03*
X1127531D03*
Y21126D03*
X1125031D03*
Y18126D03*
X1104601Y53737D03*
Y56737D03*
X1107101Y53737D03*
Y56737D03*
X1132670Y35582D03*
X1135170D03*
Y38582D03*
X1132670D03*
X1135031Y21126D03*
Y18126D03*
X1132531Y21126D03*
Y18126D03*
X1132950Y82867D03*
Y85867D03*
X1135450D03*
Y82867D03*
X1137950D03*
X1140450D03*
X1142950D03*
Y85867D03*
X1140450D03*
X1137950D03*
X1183321Y123652D03*
X1185821D03*
X1188321D03*
Y120652D03*
X1185821D03*
X1183321D03*
X1180821D03*
Y123652D03*
X1178321D03*
Y120652D03*
G54D10*
X3005Y19808D03*
Y34808D03*
Y59808D03*
X7595Y128373D03*
X3005Y145238D03*
Y165238D03*
Y185238D03*
Y205238D03*
Y225238D03*
Y245238D03*
Y265238D03*
Y285238D03*
Y305238D03*
Y325238D03*
Y345238D03*
Y365238D03*
Y385238D03*
Y405238D03*
Y425238D03*
Y445238D03*
X3023Y524312D03*
Y549312D03*
X4540Y566003D03*
X34582Y3004D03*
X14811Y3732D03*
X12767Y72072D03*
X27271Y127298D03*
X19558Y454589D03*
X9913Y510026D03*
X20498Y575739D03*
X54582Y3004D03*
X39549Y454916D03*
X40498Y575739D03*
X60498D03*
X94582Y3004D03*
X74582D03*
X80498Y575739D03*
X114582Y3004D03*
X100498Y575739D03*
X120498D03*
X154582Y3004D03*
X134582D03*
X140400Y258360D03*
X143400D03*
X140400Y261360D03*
X143400D03*
X140400Y255360D03*
X143400D03*
X140498Y575739D03*
X174582Y3004D03*
X184349Y212651D03*
X173265Y340552D03*
X183539Y518000D03*
X180539D03*
X214582Y3004D03*
X194582D03*
X189760Y242100D03*
Y245100D03*
X192760Y242100D03*
Y245100D03*
X195760Y242100D03*
Y245100D03*
X198760Y242100D03*
Y245100D03*
X201760Y242100D03*
Y245100D03*
X208071Y305975D03*
X234582Y3004D03*
X246000Y238500D03*
X242500Y243000D03*
Y247500D03*
X218500Y305000D03*
X226975D03*
X235975D03*
X239567Y305975D03*
X223819Y445025D03*
X231539Y518000D03*
X228539D03*
X254582Y3004D03*
X246000Y235500D03*
X294582Y3004D03*
X274582D03*
X297000Y206000D03*
Y203500D03*
Y198500D03*
Y196000D03*
X290720Y340338D03*
X279539Y518000D03*
X276539D03*
X314582Y3004D03*
X318500Y206000D03*
Y203500D03*
Y198500D03*
Y196000D03*
X313571Y340552D03*
X354582Y3004D03*
X334582D03*
X340000Y206000D03*
Y203500D03*
Y198500D03*
Y196000D03*
X361500Y206000D03*
Y203500D03*
Y198500D03*
Y196000D03*
X341019Y518000D03*
X338019D03*
X374582Y3004D03*
X383000Y206000D03*
Y203500D03*
Y198500D03*
Y196000D03*
X375475Y305000D03*
X383975D03*
X365551Y305975D03*
X381299Y445025D03*
X389019Y518000D03*
X386019D03*
X414582Y3004D03*
X394582D03*
X404500Y206000D03*
Y203500D03*
Y198500D03*
Y196000D03*
X402000Y235000D03*
Y238000D03*
X398500Y247000D03*
Y242500D03*
X393000Y305000D03*
X397047Y305975D03*
X434582Y3004D03*
X426000Y206000D03*
Y203500D03*
Y198500D03*
Y196000D03*
X447255Y340339D03*
X430019Y444260D03*
X432019Y452025D03*
X437019Y518000D03*
X434019D03*
X474582Y3004D03*
X454582D03*
X473095Y340339D03*
X494582Y3004D03*
X498500Y518000D03*
X495500D03*
X534582Y3004D03*
X514582D03*
X533475Y305500D03*
X523032Y305975D03*
X538780Y445025D03*
X554582Y3004D03*
X555500Y239000D03*
Y236000D03*
X552000Y243500D03*
Y247000D03*
X542475Y305500D03*
X551475D03*
X554528Y305975D03*
X545063Y340339D03*
X549500Y445024D03*
X546500Y518000D03*
X543500D03*
X594582Y3004D03*
X574582D03*
X587500Y444260D03*
X589500Y446500D03*
X594500Y518000D03*
X591500D03*
X614582Y3004D03*
X604500Y205500D03*
Y203000D03*
Y198000D03*
Y195500D03*
X626000Y205500D03*
Y203000D03*
Y198000D03*
Y195500D03*
X654582Y3004D03*
X634582D03*
X647975Y37000D03*
X660200Y56800D03*
X655300D03*
X652300D03*
X647500Y205500D03*
Y203000D03*
Y198000D03*
Y195500D03*
X655981Y518000D03*
X652981D03*
X674582Y3004D03*
X684525Y32500D03*
Y36500D03*
X683600Y56800D03*
X679000D03*
X676000D03*
X686500D03*
X671100D03*
X668100D03*
X663200D03*
X669000Y205500D03*
Y203000D03*
Y198000D03*
Y195500D03*
X680513Y305975D03*
X714582Y3004D03*
X694582D03*
X699500Y34500D03*
X696900Y53300D03*
X694200D03*
X691400D03*
X689900Y56600D03*
X693000D03*
X696100Y56700D03*
X706000Y61975D03*
X690500Y205500D03*
Y203000D03*
Y198000D03*
Y195500D03*
X711990D03*
Y198000D03*
Y203000D03*
Y205500D03*
X709500Y247000D03*
X709481Y243500D03*
X712981Y236000D03*
Y239000D03*
X712009Y305975D03*
X708956Y305500D03*
X690956D03*
X700000D03*
X696261Y445024D03*
X703981Y518000D03*
X700981D03*
X734582Y3004D03*
X733490Y195500D03*
Y198000D03*
Y203000D03*
Y205500D03*
X732100Y332400D03*
X742500Y361500D03*
X774582Y3004D03*
X754582D03*
X761560Y38500D03*
X758760D03*
X756160D03*
X761560Y30000D03*
X758760D03*
X756160D03*
X758900Y27400D03*
X761560Y55500D03*
X758760D03*
X756160D03*
X761560Y47000D03*
X758760D03*
X756160D03*
X761560Y64000D03*
X758760D03*
X756160D03*
X751981Y518000D03*
X748981D03*
X794582Y3004D03*
X797854Y259539D03*
X786500Y336484D03*
X834582Y3004D03*
X814582D03*
X809500Y259430D03*
X819500Y329000D03*
X827500D03*
X813975Y362000D03*
Y357000D03*
X854582Y3004D03*
X849490Y196000D03*
Y198500D03*
Y203500D03*
Y206000D03*
X846000Y260525D03*
X851000D03*
X856000D03*
X837575Y321000D03*
X844760Y336077D03*
X850500Y360075D03*
Y366000D03*
X847500D03*
X856500D03*
X859500D03*
X865500D03*
X894582Y3004D03*
X874582D03*
X894500Y283475D03*
X884000D03*
X877500D03*
X893363Y298740D03*
X883000Y293925D03*
X877500Y366000D03*
X874500D03*
X884000D03*
X887000D03*
X893500D03*
X868500D03*
X914582Y3004D03*
X915500Y283475D03*
X914500Y292000D03*
X905000Y283475D03*
X905941Y306500D03*
X916260Y337077D03*
X908000Y327975D03*
X896500Y366000D03*
X906000D03*
X903000D03*
X912500D03*
X915500D03*
X922000D03*
X901063Y352340D03*
X934582Y3004D03*
X933000Y293476D03*
X940000D03*
X947000D03*
X933196Y309910D03*
X925000Y366000D03*
X944000D03*
X941000D03*
X934500D03*
X950500D03*
X953500D03*
X931500D03*
X927000Y361075D03*
X940498Y575739D03*
X974582Y3004D03*
X954582D03*
X960498Y575739D03*
X980498D03*
X994582Y3004D03*
X1000498Y575739D03*
X1034582Y3004D03*
X1014582D03*
X1034500Y142000D03*
X1020498Y575739D03*
X1040498D03*
X1054582Y3004D03*
X1068900Y110000D03*
X1065000Y156425D03*
X1070715Y178585D03*
X1060498Y575739D03*
X1094582Y3004D03*
X1074582D03*
X1091000Y99500D03*
X1095100D03*
X1073200Y126000D03*
Y128800D03*
Y123200D03*
X1084740Y108000D03*
X1100075Y139925D03*
X1084260Y152600D03*
X1101903Y285019D03*
X1101796Y331894D03*
X1090500Y376500D03*
X1090443Y417343D03*
X1080498Y575739D03*
X1100498D03*
X1114582Y3004D03*
X1113000Y101240D03*
X1119500Y86000D03*
Y83000D03*
X1113500Y147500D03*
X1118774Y284699D03*
X1112902D03*
X1110019Y284806D03*
X1104786Y284912D03*
X1121657Y284592D03*
X1118667Y331574D03*
X1112795D03*
X1109912Y331681D03*
X1104679Y331787D03*
X1121550Y331467D03*
X1104009Y427245D03*
X1120880Y426925D03*
X1115008D03*
X1112125Y427032D03*
X1106892Y427138D03*
X1123763Y426818D03*
X1103800Y474339D03*
X1106683Y474232D03*
X1111916Y474126D03*
X1114799Y474019D03*
X1120671D03*
X1123554Y473912D03*
X1120498Y575739D03*
X1154582Y3004D03*
X1134582D03*
X1155000Y124913D03*
X1159300Y129700D03*
X1141500Y124425D03*
Y120500D03*
X1154000Y151500D03*
X1141500Y134575D03*
X1138203Y266860D03*
Y260860D03*
Y263860D03*
X1135203Y260860D03*
Y263860D03*
Y266860D03*
X1138203Y257860D03*
Y254860D03*
X1135203Y257860D03*
Y254860D03*
X1135403Y302360D03*
Y305360D03*
X1138403Y302360D03*
Y305360D03*
X1135403Y308360D03*
X1138403D03*
X1135403Y314360D03*
Y311360D03*
X1138403D03*
Y314360D03*
Y361979D03*
X1135403D03*
X1138403Y358979D03*
X1135403D03*
X1138403Y355979D03*
X1135403D03*
X1138403Y352979D03*
X1135403D03*
X1138403Y349979D03*
X1135403D03*
X1135190Y396965D03*
X1138190D03*
X1135190Y399965D03*
X1138190D03*
X1135190Y402965D03*
Y405965D03*
Y408965D03*
X1138190Y402965D03*
Y405965D03*
Y408965D03*
X1135404Y457228D03*
Y454228D03*
Y451228D03*
Y445228D03*
Y448228D03*
X1138404Y454228D03*
Y451228D03*
Y445228D03*
Y448228D03*
Y457228D03*
X1135622Y485732D03*
Y470732D03*
Y467732D03*
Y479732D03*
Y476732D03*
Y473732D03*
Y482732D03*
X1138622D03*
Y473732D03*
Y476732D03*
Y479732D03*
Y470732D03*
Y485732D03*
Y467732D03*
X1140498Y575739D03*
X1160498D03*
X1174582Y3004D03*
X1177475Y111500D03*
X1179500Y105500D03*
X1180498Y575739D03*
X1214582Y3004D03*
X1194582D03*
X1203887Y306894D03*
X1200887D03*
X1197887D03*
X1203887Y303894D03*
X1200887D03*
X1197887D03*
X1203887Y300894D03*
X1200887D03*
X1197887D03*
X1203887Y297894D03*
X1200887D03*
X1197887D03*
X1203887Y294894D03*
X1200887D03*
X1197887D03*
Y321894D03*
X1200887D03*
X1203887D03*
Y318894D03*
X1200887D03*
X1197887D03*
X1203887Y315894D03*
X1200887D03*
X1197887D03*
X1203887Y312894D03*
X1200887D03*
X1197887D03*
X1203887Y309894D03*
X1200887D03*
X1197887D03*
X1197976Y437394D03*
X1200976D03*
X1203976D03*
X1197976Y440394D03*
X1200976D03*
X1203976D03*
X1197976Y443394D03*
X1200976D03*
X1203976D03*
X1197976Y446394D03*
X1200976D03*
X1203976D03*
X1197976Y449394D03*
X1200976D03*
X1203976D03*
X1197976Y452394D03*
X1200976D03*
X1203976D03*
X1197976Y455394D03*
X1200976D03*
X1203976D03*
X1197976Y464394D03*
X1200976D03*
X1203976D03*
X1197976Y458394D03*
X1200976D03*
X1203976D03*
X1197976Y461394D03*
X1200976D03*
X1203976D03*
X1200498Y575739D03*
X1220498D03*
X1234582Y3004D03*
X1240498Y575739D03*
X1277657Y4128D03*
X1254582Y3004D03*
X1260498Y575739D03*
X1279438Y573806D03*
X1286766Y12634D03*
X1288331Y30962D03*
Y70962D03*
Y50962D03*
Y90962D03*
Y130962D03*
Y110962D03*
Y150962D03*
Y190962D03*
Y170962D03*
Y210962D03*
Y230962D03*
Y270962D03*
Y250962D03*
Y290962D03*
Y330962D03*
Y310962D03*
Y350962D03*
Y390962D03*
Y370962D03*
Y410962D03*
Y450962D03*
Y430962D03*
Y470962D03*
Y510962D03*
Y490962D03*
Y530962D03*
X1287616Y563889D03*
X1288331Y550962D03*
G54D42*
X812559Y139408D03*
X852559Y129408D03*
Y119408D03*
X862559Y129408D03*
Y119408D03*
X852559Y149408D03*
Y139408D03*
X862559Y149408D03*
Y139408D03*
X887559Y129408D03*
Y119408D03*
Y149408D03*
Y139408D03*
X897559Y129408D03*
Y119408D03*
X922559Y129408D03*
Y119408D03*
X897559Y149408D03*
Y139408D03*
X922559Y149408D03*
Y139408D03*
X932559Y129408D03*
Y119408D03*
Y149408D03*
Y139408D03*
G54D48*
X1226024Y174429D03*
Y399429D03*
G54D18*
X33780Y324724D03*
G54D34*
X268000Y220315D03*
X312500D03*
X357000D03*
X428500D03*
X472500D03*
X516500D03*
X578500D03*
X622500D03*
X666500D03*
X735981D03*
X779981D03*
X823981D03*
G54D15*
X38780Y232598D03*
Y239291D03*
Y252598D03*
Y259291D03*
X48780Y232598D03*
Y239291D03*
Y252598D03*
Y259291D03*
G54D47*
X1240158Y57480D03*
Y521260D03*
G54D31*
X193819Y477204D03*
X351299D03*
X508780D03*
X666261D03*
G54D39*
X753314Y607542D03*
G54D41*
X753420Y635687D03*
%LPC*%
G75*
G54D50*
G01X-297025Y-1013390D02*
Y1828909D01*
X3691357D01*
Y-1013390D01*
X-297025D01*
G01X4093Y-769672D02*
Y-844672D01*
X504093D01*
Y-769672D01*
X4093D01*
G01X16093Y-834672D02*
Y-839672D01*
G01X14636Y-834672D02*
X17550D01*
G01X22460Y-839672D02*
X19926D01*
Y-834672D01*
X22460D01*
G01X21446Y-837089D02*
X19926D01*
G01X25026Y-834672D02*
Y-839672D01*
X27560D01*
G01X31393Y-839839D02*
X31266Y-839755D01*
Y-839589D01*
X31393Y-839505D01*
X31520Y-839589D01*
Y-839755D01*
X31393Y-839839D01*
G01Y-837589D02*
X31266Y-837505D01*
Y-837339D01*
X31393Y-837255D01*
X31520Y-837339D01*
Y-837505D01*
X31393Y-837589D01*
G01X36176Y-841339D02*
X35543Y-840505D01*
X35226Y-839672D01*
Y-836339D01*
X35543Y-835505D01*
X36176Y-834672D01*
G01X41593D02*
X41086Y-834839D01*
X40706Y-835255D01*
X40453Y-835755D01*
X40263Y-836422D01*
X40200Y-837172D01*
X40263Y-837922D01*
X40453Y-838589D01*
X40706Y-839089D01*
X41086Y-839505D01*
X41593Y-839672D01*
X42100Y-839505D01*
X42480Y-839089D01*
X42733Y-838589D01*
X42923Y-837922D01*
X42986Y-837172D01*
X42923Y-836422D01*
X42733Y-835755D01*
X42480Y-835255D01*
X42100Y-834839D01*
X41593Y-834672D01*
G01X45300Y-838672D02*
X45680Y-839255D01*
X46186Y-839589D01*
X46756Y-839672D01*
X47263Y-839589D01*
X47770Y-839172D01*
X48086Y-838672D01*
X48150Y-838172D01*
X48023Y-837589D01*
X47580Y-837172D01*
X47136Y-837005D01*
X46566D01*
G01X47136D02*
X47516Y-836755D01*
X47833Y-836339D01*
X47960Y-835839D01*
X47833Y-835339D01*
X47516Y-834922D01*
X46946Y-834672D01*
X46376Y-834755D01*
X45806Y-835089D01*
G01X52110Y-841339D02*
X52743Y-840505D01*
X53060Y-839672D01*
Y-836339D01*
X52743Y-835505D01*
X52110Y-834672D01*
G01X55500Y-838672D02*
X55880Y-839255D01*
X56386Y-839589D01*
X56956Y-839672D01*
X57463Y-839589D01*
X57970Y-839172D01*
X58286Y-838672D01*
X58350Y-838172D01*
X58223Y-837589D01*
X57780Y-837172D01*
X57336Y-837005D01*
X56766D01*
G01X57336D02*
X57716Y-836755D01*
X58033Y-836339D01*
X58160Y-835839D01*
X58033Y-835339D01*
X57716Y-834922D01*
X57146Y-834672D01*
X56576Y-834755D01*
X56006Y-835089D01*
G01X60790Y-835505D02*
X61170Y-835005D01*
X61613Y-834755D01*
X62120Y-834672D01*
X62753Y-834839D01*
X63196Y-835255D01*
X63323Y-835755D01*
X63260Y-836255D01*
X63006Y-836672D01*
X61740Y-837505D01*
X61170Y-838089D01*
X60790Y-838922D01*
X60663Y-839672D01*
X63323D01*
G01X66966D02*
X67093Y-838589D01*
X67283Y-837672D01*
X67536Y-836839D01*
X67853Y-835922D01*
X68360Y-834672D01*
X65826D01*
G01X71370Y-838005D02*
X73016D01*
G01X76090Y-835505D02*
X76470Y-835005D01*
X76913Y-834755D01*
X77420Y-834672D01*
X78053Y-834839D01*
X78496Y-835255D01*
X78623Y-835755D01*
X78560Y-836255D01*
X78306Y-836672D01*
X77040Y-837505D01*
X76470Y-838089D01*
X76090Y-838922D01*
X75963Y-839672D01*
X78623D01*
G01X81000Y-838672D02*
X81380Y-839255D01*
X81886Y-839589D01*
X82456Y-839672D01*
X82963Y-839589D01*
X83470Y-839172D01*
X83786Y-838672D01*
X83850Y-838172D01*
X83723Y-837589D01*
X83280Y-837172D01*
X82836Y-837005D01*
X82266D01*
G01X82836D02*
X83216Y-836755D01*
X83533Y-836339D01*
X83660Y-835839D01*
X83533Y-835339D01*
X83216Y-834922D01*
X82646Y-834672D01*
X82076Y-834755D01*
X81506Y-835089D01*
G01X88253Y-839672D02*
Y-834672D01*
X85910Y-838255D01*
X89076D01*
G01X91200Y-838922D02*
X91580Y-839339D01*
X92023Y-839589D01*
X92593Y-839672D01*
X93163Y-839505D01*
X93606Y-839172D01*
X93923Y-838589D01*
X93986Y-837922D01*
X93860Y-837255D01*
X93543Y-836839D01*
X93100Y-836505D01*
X92656Y-836422D01*
X92213Y-836505D01*
X91643Y-836839D01*
X91833Y-834672D01*
X93543D01*
G01X101590Y-839672D02*
Y-834672D01*
X103996D01*
G01X103110Y-837089D02*
X101590D01*
G01X106310Y-839672D02*
X107893Y-834672D01*
X109476Y-839672D01*
G01X108906Y-837922D02*
X106880D01*
G01X111663Y-839672D02*
X114323Y-834672D01*
G01X111663D02*
X114323Y-839672D01*
G01X118093Y-839839D02*
X117966Y-839755D01*
Y-839589D01*
X118093Y-839505D01*
X118220Y-839589D01*
Y-839755D01*
X118093Y-839839D01*
G01Y-837589D02*
X117966Y-837505D01*
Y-837339D01*
X118093Y-837255D01*
X118220Y-837339D01*
Y-837505D01*
X118093Y-837589D01*
G01X122876Y-841339D02*
X122243Y-840505D01*
X121926Y-839672D01*
Y-836339D01*
X122243Y-835505D01*
X122876Y-834672D01*
G01X128293D02*
X127786Y-834839D01*
X127406Y-835255D01*
X127153Y-835755D01*
X126963Y-836422D01*
X126900Y-837172D01*
X126963Y-837922D01*
X127153Y-838589D01*
X127406Y-839089D01*
X127786Y-839505D01*
X128293Y-839672D01*
X128800Y-839505D01*
X129180Y-839089D01*
X129433Y-838589D01*
X129623Y-837922D01*
X129686Y-837172D01*
X129623Y-836422D01*
X129433Y-835755D01*
X129180Y-835255D01*
X128800Y-834839D01*
X128293Y-834672D01*
G01X132000Y-838672D02*
X132380Y-839255D01*
X132886Y-839589D01*
X133456Y-839672D01*
X133963Y-839589D01*
X134470Y-839172D01*
X134786Y-838672D01*
X134850Y-838172D01*
X134723Y-837589D01*
X134280Y-837172D01*
X133836Y-837005D01*
X133266D01*
G01X133836D02*
X134216Y-836755D01*
X134533Y-836339D01*
X134660Y-835839D01*
X134533Y-835339D01*
X134216Y-834922D01*
X133646Y-834672D01*
X133076Y-834755D01*
X132506Y-835089D01*
G01X138810Y-841339D02*
X139443Y-840505D01*
X139760Y-839672D01*
Y-836339D01*
X139443Y-835505D01*
X138810Y-834672D01*
G01X142200Y-838672D02*
X142580Y-839255D01*
X143086Y-839589D01*
X143656Y-839672D01*
X144163Y-839589D01*
X144670Y-839172D01*
X144986Y-838672D01*
X145050Y-838172D01*
X144923Y-837589D01*
X144480Y-837172D01*
X144036Y-837005D01*
X143466D01*
G01X144036D02*
X144416Y-836755D01*
X144733Y-836339D01*
X144860Y-835839D01*
X144733Y-835339D01*
X144416Y-834922D01*
X143846Y-834672D01*
X143276Y-834755D01*
X142706Y-835089D01*
G01X147616Y-839089D02*
X148060Y-839505D01*
X148566Y-839672D01*
X149073Y-839505D01*
X149516Y-839005D01*
X149833Y-838255D01*
X149960Y-837505D01*
Y-836589D01*
X149833Y-835839D01*
X149516Y-835172D01*
X149136Y-834839D01*
X148693Y-834672D01*
X148186Y-834839D01*
X147806Y-835172D01*
X147553Y-835672D01*
X147426Y-836339D01*
X147553Y-836922D01*
X147870Y-837505D01*
X148250Y-837839D01*
X148693Y-837922D01*
X149200Y-837755D01*
X149580Y-837339D01*
X149960Y-836589D01*
G01X153666Y-839672D02*
X153793Y-838589D01*
X153983Y-837672D01*
X154236Y-836839D01*
X154553Y-835922D01*
X155060Y-834672D01*
X152526D01*
G01X158070Y-838005D02*
X159716D01*
G01X162600Y-838672D02*
X162980Y-839255D01*
X163486Y-839589D01*
X164056Y-839672D01*
X164563Y-839589D01*
X165070Y-839172D01*
X165386Y-838672D01*
X165450Y-838172D01*
X165323Y-837589D01*
X164880Y-837172D01*
X164436Y-837005D01*
X163866D01*
G01X164436D02*
X164816Y-836755D01*
X165133Y-836339D01*
X165260Y-835839D01*
X165133Y-835339D01*
X164816Y-834922D01*
X164246Y-834672D01*
X163676Y-834755D01*
X163106Y-835089D01*
G01X167890Y-837589D02*
X168333Y-837005D01*
X168713Y-836672D01*
X169220Y-836505D01*
X169663Y-836672D01*
X169980Y-837005D01*
X170233Y-837505D01*
X170296Y-838089D01*
X170233Y-838589D01*
X169980Y-839089D01*
X169600Y-839505D01*
X169156Y-839672D01*
X168650Y-839505D01*
X168206Y-839005D01*
X167953Y-838255D01*
X167890Y-837422D01*
X168016Y-836339D01*
X168206Y-835755D01*
X168523Y-835172D01*
X168966Y-834755D01*
X169410Y-834672D01*
X169853Y-834839D01*
X170170Y-835255D01*
G01X174193Y-839672D02*
Y-834672D01*
X173433Y-835672D01*
G01Y-839672D02*
X174953D01*
G01X180053D02*
Y-834672D01*
X177710Y-838255D01*
X180876D01*
G01X199093Y-769672D02*
Y-844672D01*
G01Y-819672D02*
X302093D01*
Y-794672D01*
G01X199093D02*
X302093D01*
G01X309600Y-829672D02*
Y-824672D01*
X310866D01*
X311373Y-824922D01*
X311753Y-825255D01*
X312070Y-825755D01*
X312323Y-826339D01*
X312386Y-827172D01*
X312323Y-828005D01*
X312070Y-828589D01*
X311753Y-829089D01*
X311373Y-829422D01*
X310866Y-829672D01*
X309600D01*
G01X314510D02*
X316093Y-824672D01*
X317676Y-829672D01*
G01X317106Y-827922D02*
X315080D01*
G01X321193Y-824672D02*
Y-829672D01*
G01X319736Y-824672D02*
X322650D01*
G01X327560Y-829672D02*
X325026D01*
Y-824672D01*
X327560D01*
G01X326546Y-827089D02*
X325026D01*
G01X331393Y-829839D02*
X331266Y-829755D01*
Y-829589D01*
X331393Y-829505D01*
X331520Y-829589D01*
Y-829755D01*
X331393Y-829839D01*
G01Y-827589D02*
X331266Y-827505D01*
Y-827339D01*
X331393Y-827255D01*
X331520Y-827339D01*
Y-827505D01*
X331393Y-827589D01*
G01X304093Y-769672D02*
Y-844672D01*
G01X302093Y-769672D02*
Y-844672D01*
G01X304093Y-819672D02*
X504093D01*
G01X309726Y-804672D02*
Y-799672D01*
X311246D01*
X311753Y-799922D01*
X312133Y-800505D01*
X312260Y-801172D01*
X312133Y-801839D01*
X311816Y-802339D01*
X311246Y-802589D01*
X309726D01*
G01X314953Y-804839D02*
X317233Y-799672D01*
G01X319736Y-804672D02*
Y-799672D01*
X322650Y-804672D01*
Y-799672D01*
G01X326293Y-804839D02*
X326166Y-804755D01*
Y-804589D01*
X326293Y-804505D01*
X326420Y-804589D01*
Y-804755D01*
X326293Y-804839D01*
G01Y-802589D02*
X326166Y-802505D01*
Y-802339D01*
X326293Y-802255D01*
X326420Y-802339D01*
Y-802505D01*
X326293Y-802589D01*
G01X304093Y-794672D02*
X504093D01*
G01X309726Y-779672D02*
Y-774672D01*
X311246D01*
X311753Y-774922D01*
X312133Y-775505D01*
X312260Y-776172D01*
X312133Y-776839D01*
X311816Y-777339D01*
X311246Y-777589D01*
X309726D01*
G01X314826Y-779672D02*
Y-774672D01*
X316410D01*
X316916Y-774922D01*
X317233Y-775255D01*
X317360Y-775922D01*
X317233Y-776589D01*
X316853Y-777005D01*
X316410Y-777255D01*
X314826D01*
G01X316410D02*
X317360Y-779672D01*
G01X321193D02*
X320686Y-779589D01*
X320243Y-779255D01*
X319863Y-778755D01*
X319610Y-778172D01*
X319483Y-777505D01*
Y-776839D01*
X319610Y-776172D01*
X319863Y-775589D01*
X320243Y-775089D01*
X320686Y-774755D01*
X321193Y-774672D01*
X321700Y-774755D01*
X322143Y-775089D01*
X322523Y-775589D01*
X322776Y-776172D01*
X322903Y-776839D01*
Y-777505D01*
X322776Y-778172D01*
X322523Y-778755D01*
X322143Y-779255D01*
X321700Y-779589D01*
X321193Y-779672D01*
G01X325026Y-778672D02*
X325343Y-779172D01*
X325723Y-779505D01*
X326166Y-779672D01*
X326673Y-779505D01*
X327053Y-779172D01*
X327433Y-778672D01*
X327560Y-778005D01*
Y-774672D01*
G01X332660Y-779672D02*
X330126D01*
Y-774672D01*
X332660D01*
G01X331646Y-777089D02*
X330126D01*
G01X337886Y-775089D02*
X337506Y-774839D01*
X337063Y-774672D01*
X336556D01*
X335986Y-774922D01*
X335543Y-775339D01*
X335226Y-775839D01*
X334973Y-776672D01*
X334910Y-777422D01*
X335036Y-778172D01*
X335226Y-778672D01*
X335606Y-779172D01*
X336050Y-779505D01*
X336493Y-779672D01*
X336936D01*
X337380Y-779505D01*
X337760Y-779255D01*
X338076Y-778922D01*
G01X341593Y-774672D02*
Y-779672D01*
G01X340136Y-774672D02*
X343050D01*
G01X346693Y-779839D02*
X346566Y-779755D01*
Y-779589D01*
X346693Y-779505D01*
X346820Y-779589D01*
Y-779755D01*
X346693Y-779839D01*
G01Y-777589D02*
X346566Y-777505D01*
Y-777339D01*
X346693Y-777255D01*
X346820Y-777339D01*
Y-777505D01*
X346693Y-777589D01*
G01X419093Y-819672D02*
Y-844672D01*
G01X421726Y-822172D02*
Y-827172D01*
X424260D01*
G01X427333Y-822172D02*
X428853D01*
G01X428093D02*
Y-827172D01*
G01X427333D02*
X428853D01*
G01X433700Y-824505D02*
X433953Y-824255D01*
X434143Y-823839D01*
X434270Y-823255D01*
X434143Y-822755D01*
X433890Y-822422D01*
X433446Y-822172D01*
X431736D01*
Y-827172D01*
X433826D01*
X434270Y-826839D01*
X434523Y-826339D01*
X434650Y-825755D01*
X434523Y-825172D01*
X434143Y-824672D01*
X433700Y-824505D01*
X431736D01*
G01X438293Y-827339D02*
X438166Y-827255D01*
Y-827089D01*
X438293Y-827005D01*
X438420Y-827089D01*
Y-827255D01*
X438293Y-827339D01*
G01Y-825089D02*
X438166Y-825005D01*
Y-824839D01*
X438293Y-824755D01*
X438420Y-824839D01*
Y-825005D01*
X438293Y-825089D01*
G01X470106Y-847839D02*
X470213Y-847714D01*
X470293Y-847505D01*
X470346Y-847214D01*
X470293Y-846964D01*
X470186Y-846797D01*
X470000Y-846672D01*
X469280D01*
Y-849172D01*
X470160D01*
X470346Y-849005D01*
X470453Y-848755D01*
X470506Y-848464D01*
X470453Y-848172D01*
X470293Y-847922D01*
X470106Y-847839D01*
X469280D01*
G01X472573Y-849172D02*
Y-847505D01*
G01Y-847797D02*
X472466Y-847630D01*
X472306Y-847547D01*
X472120Y-847505D01*
X471933Y-847589D01*
X471773Y-847755D01*
X471666Y-848005D01*
X471613Y-848339D01*
X471666Y-848672D01*
X471773Y-848922D01*
X471933Y-849089D01*
X472120Y-849172D01*
X472306Y-849130D01*
X472466Y-849005D01*
X472573Y-848839D01*
G01X473893Y-848880D02*
X474026Y-849047D01*
X474213Y-849172D01*
X474373D01*
X474533Y-849089D01*
X474640Y-848964D01*
X474693Y-848797D01*
X474666Y-848547D01*
X474560Y-848422D01*
X474080Y-848172D01*
X473973Y-847880D01*
X474026Y-847672D01*
X474133Y-847547D01*
X474293Y-847505D01*
X474453Y-847547D01*
X474613Y-847672D01*
G01X476093Y-848047D02*
X476946D01*
X476866Y-847755D01*
X476733Y-847589D01*
X476546Y-847505D01*
X476360Y-847547D01*
X476200Y-847672D01*
X476093Y-847964D01*
X476040Y-848214D01*
Y-848464D01*
X476093Y-848714D01*
X476226Y-848964D01*
X476386Y-849130D01*
X476573Y-849172D01*
X476760Y-849089D01*
X476946Y-848839D01*
G01X478213Y-849172D02*
Y-846672D01*
G01Y-847922D02*
X478346Y-847672D01*
X478506Y-847547D01*
X478666Y-847505D01*
X478906Y-847589D01*
X479066Y-847755D01*
X479173Y-848047D01*
Y-848380D01*
X479120Y-848714D01*
X479013Y-848964D01*
X478826Y-849130D01*
X478666Y-849172D01*
X478506Y-849130D01*
X478346Y-849005D01*
X478213Y-848797D01*
G01X480893Y-849172D02*
X480733Y-849130D01*
X480573Y-848964D01*
X480466Y-848672D01*
X480413Y-848339D01*
X480466Y-848005D01*
X480573Y-847714D01*
X480733Y-847547D01*
X480893Y-847505D01*
X481053Y-847547D01*
X481213Y-847714D01*
X481320Y-848005D01*
X481346Y-848339D01*
X481320Y-848672D01*
X481213Y-848964D01*
X481053Y-849130D01*
X480893Y-849172D01*
G01X483573D02*
Y-847505D01*
G01Y-847797D02*
X483466Y-847630D01*
X483306Y-847547D01*
X483120Y-847505D01*
X482933Y-847589D01*
X482773Y-847755D01*
X482666Y-848005D01*
X482613Y-848339D01*
X482666Y-848672D01*
X482773Y-848922D01*
X482933Y-849089D01*
X483120Y-849172D01*
X483306Y-849130D01*
X483466Y-849005D01*
X483573Y-848839D01*
G01X484920Y-849172D02*
Y-847505D01*
G01Y-847839D02*
X485053Y-847672D01*
X485186Y-847547D01*
X485373Y-847505D01*
X485506Y-847547D01*
X485666Y-847672D01*
G01X487973Y-846672D02*
Y-849172D01*
G01Y-848797D02*
X487866Y-849005D01*
X487706Y-849130D01*
X487520Y-849172D01*
X487306Y-849089D01*
X487146Y-848880D01*
X487040Y-848630D01*
X487013Y-848339D01*
X487040Y-848047D01*
X487146Y-847797D01*
X487306Y-847589D01*
X487520Y-847505D01*
X487706Y-847547D01*
X487840Y-847630D01*
X487973Y-847797D01*
G01X491360Y-849172D02*
Y-846672D01*
X492026D01*
X492240Y-846797D01*
X492373Y-846964D01*
X492426Y-847297D01*
X492373Y-847630D01*
X492213Y-847839D01*
X492026Y-847964D01*
X491360D01*
G01X492026D02*
X492426Y-849172D01*
G01X493693Y-848047D02*
X494546D01*
X494466Y-847755D01*
X494333Y-847589D01*
X494146Y-847505D01*
X493960Y-847547D01*
X493800Y-847672D01*
X493693Y-847964D01*
X493640Y-848214D01*
Y-848464D01*
X493693Y-848714D01*
X493826Y-848964D01*
X493986Y-849130D01*
X494173Y-849172D01*
X494360Y-849089D01*
X494546Y-848839D01*
G01X495813Y-847505D02*
X496293Y-849172D01*
X496773Y-847505D01*
G01X498493Y-849255D02*
X498440Y-849214D01*
Y-849130D01*
X498493Y-849089D01*
X498546Y-849130D01*
Y-849214D01*
X498493Y-849255D01*
G01X500693Y-849172D02*
X500880Y-849130D01*
X501093Y-849005D01*
X501226Y-848797D01*
X501280Y-848505D01*
X501226Y-848214D01*
X501066Y-847964D01*
X500826Y-847839D01*
X500560D01*
X500400Y-847755D01*
X500266Y-847547D01*
X500213Y-847255D01*
X500293Y-846964D01*
X500480Y-846755D01*
X500693Y-846672D01*
X500906Y-846755D01*
X501093Y-846964D01*
X501173Y-847255D01*
X501120Y-847547D01*
X500986Y-847755D01*
X500826Y-847839D01*
X500560D01*
X500320Y-847964D01*
X500160Y-848214D01*
X500106Y-848505D01*
X500160Y-848797D01*
X500293Y-849005D01*
X500506Y-849130D01*
X500693Y-849172D01*
G01X503106Y-847839D02*
X503213Y-847714D01*
X503293Y-847505D01*
X503346Y-847214D01*
X503293Y-846964D01*
X503186Y-846797D01*
X503000Y-846672D01*
X502280D01*
Y-849172D01*
X503160D01*
X503346Y-849005D01*
X503453Y-848755D01*
X503506Y-848464D01*
X503453Y-848172D01*
X503293Y-847922D01*
X503106Y-847839D01*
X502280D01*
G01X465993Y-822172D02*
Y-827172D01*
G01X464536Y-822172D02*
X467450D01*
G01X471093Y-827172D02*
X470713Y-827089D01*
X470333Y-826755D01*
X470080Y-826172D01*
X469953Y-825505D01*
X470080Y-824839D01*
X470333Y-824255D01*
X470713Y-823922D01*
X471093Y-823839D01*
X471473Y-823922D01*
X471853Y-824255D01*
X472106Y-824839D01*
X472170Y-825505D01*
X472106Y-826172D01*
X471853Y-826755D01*
X471473Y-827089D01*
X471093Y-827172D01*
G01X476193D02*
X475813Y-827089D01*
X475433Y-826755D01*
X475180Y-826172D01*
X475053Y-825505D01*
X475180Y-824839D01*
X475433Y-824255D01*
X475813Y-823922D01*
X476193Y-823839D01*
X476573Y-823922D01*
X476953Y-824255D01*
X477206Y-824839D01*
X477270Y-825505D01*
X477206Y-826172D01*
X476953Y-826755D01*
X476573Y-827089D01*
X476193Y-827172D01*
G01X481293D02*
Y-822172D01*
G01X486393Y-827339D02*
X486266Y-827255D01*
Y-827089D01*
X486393Y-827005D01*
X486520Y-827089D01*
Y-827255D01*
X486393Y-827339D01*
G01Y-825089D02*
X486266Y-825005D01*
Y-824839D01*
X486393Y-824755D01*
X486520Y-824839D01*
Y-825005D01*
X486393Y-825089D01*
G01X462093Y-819672D02*
Y-844672D01*
G01Y-794672D02*
Y-819672D01*
G01X464726Y-802172D02*
Y-797172D01*
X466310D01*
X466816Y-797422D01*
X467133Y-797755D01*
X467260Y-798422D01*
X467133Y-799089D01*
X466753Y-799505D01*
X466310Y-799755D01*
X464726D01*
G01X466310D02*
X467260Y-802172D01*
G01X472360D02*
X469826D01*
Y-797172D01*
X472360D01*
G01X471346Y-799589D02*
X469826D01*
G01X474610Y-797172D02*
X476193Y-802172D01*
X477776Y-797172D01*
G01X481293Y-802339D02*
X481166Y-802255D01*
Y-802089D01*
X481293Y-802005D01*
X481420Y-802089D01*
Y-802255D01*
X481293Y-802339D01*
G01Y-800089D02*
X481166Y-800005D01*
Y-799839D01*
X481293Y-799755D01*
X481420Y-799839D01*
Y-800005D01*
X481293Y-800089D01*
G01X-297025Y-1013390D02*
Y1828909D01*
X3691357D01*
Y-1013390D01*
X-297025D01*
G01X16913Y-817022D02*
X18480D01*
Y-818912D01*
X18010Y-819542D01*
X17461Y-819962D01*
X16678Y-820172D01*
X15895Y-819962D01*
X15346Y-819542D01*
X14876Y-818912D01*
X14563Y-818177D01*
X14406Y-817337D01*
Y-816602D01*
X14563Y-815972D01*
X14876Y-815237D01*
X15346Y-814607D01*
X15816Y-814187D01*
X16443Y-813872D01*
X16991D01*
X17618Y-814082D01*
X18088Y-814502D01*
G01X21020Y-813872D02*
Y-818387D01*
X21333Y-819332D01*
X21960Y-819962D01*
X22743Y-820172D01*
X23526Y-819962D01*
X24153Y-819332D01*
X24466Y-818387D01*
Y-813872D01*
G01X28103D02*
X29983D01*
G01X29043D02*
Y-820172D01*
G01X28103D02*
X29983D01*
G01X33698Y-819332D02*
X34325Y-819857D01*
X35030Y-820172D01*
X35656D01*
X36283Y-819857D01*
X36753Y-819332D01*
X36988Y-818597D01*
X36831Y-817862D01*
X36440Y-817232D01*
X35735Y-816812D01*
X34795Y-816602D01*
X34246Y-816182D01*
X34011Y-815447D01*
X34168Y-814712D01*
X34560Y-814187D01*
X35108Y-813872D01*
X35656D01*
X36205Y-814082D01*
X36675Y-814607D01*
G01X39998Y-820172D02*
Y-813872D01*
G01X43288D02*
Y-820172D01*
G01Y-817022D02*
X39998D01*
G01X45985Y-820172D02*
X47943Y-813872D01*
X49901Y-820172D01*
G01X49196Y-817967D02*
X46690D01*
G01X52441Y-820172D02*
Y-813872D01*
X56045Y-820172D01*
Y-813872D01*
G01X65120Y-820172D02*
Y-813872D01*
X66686D01*
X67313Y-814187D01*
X67783Y-814607D01*
X68175Y-815237D01*
X68488Y-815972D01*
X68566Y-817022D01*
X68488Y-818072D01*
X68175Y-818807D01*
X67783Y-819437D01*
X67313Y-819857D01*
X66686Y-820172D01*
X65120D01*
G01X72203Y-813872D02*
X74083D01*
G01X73143D02*
Y-820172D01*
G01X72203D02*
X74083D01*
G01X77798Y-819332D02*
X78425Y-819857D01*
X79130Y-820172D01*
X79756D01*
X80383Y-819857D01*
X80853Y-819332D01*
X81088Y-818597D01*
X80931Y-817862D01*
X80540Y-817232D01*
X79835Y-816812D01*
X78895Y-816602D01*
X78346Y-816182D01*
X78111Y-815447D01*
X78268Y-814712D01*
X78660Y-814187D01*
X79208Y-813872D01*
X79756D01*
X80305Y-814082D01*
X80775Y-814607D01*
G01X85743Y-813872D02*
Y-820172D01*
G01X83941Y-813872D02*
X87545D01*
G01X92043Y-820382D02*
X91886Y-820277D01*
Y-820067D01*
X92043Y-819962D01*
X92200Y-820067D01*
Y-820277D01*
X92043Y-820382D01*
G01X98186Y-821327D02*
X98500Y-819962D01*
G01X104643Y-813872D02*
Y-820172D01*
G01X102841Y-813872D02*
X106445D01*
G01X108985Y-820172D02*
X110943Y-813872D01*
X112901Y-820172D01*
G01X112196Y-817967D02*
X109690D01*
G01X117243Y-820172D02*
X116616Y-820067D01*
X116068Y-819647D01*
X115598Y-819017D01*
X115285Y-818282D01*
X115128Y-817442D01*
Y-816602D01*
X115285Y-815762D01*
X115598Y-815027D01*
X116068Y-814397D01*
X116616Y-813977D01*
X117243Y-813872D01*
X117870Y-813977D01*
X118418Y-814397D01*
X118888Y-815027D01*
X119201Y-815762D01*
X119358Y-816602D01*
Y-817442D01*
X119201Y-818282D01*
X118888Y-819017D01*
X118418Y-819647D01*
X117870Y-820067D01*
X117243Y-820172D01*
G01X123543D02*
Y-817337D01*
X121976Y-813872D01*
G01X125110D02*
X123543Y-817337D01*
G01X128120Y-813872D02*
Y-818387D01*
X128433Y-819332D01*
X129060Y-819962D01*
X129843Y-820172D01*
X130626Y-819962D01*
X131253Y-819332D01*
X131566Y-818387D01*
Y-813872D01*
G01X134185Y-820172D02*
X136143Y-813872D01*
X138101Y-820172D01*
G01X137396Y-817967D02*
X134890D01*
G01X140641Y-820172D02*
Y-813872D01*
X144245Y-820172D01*
Y-813872D01*
G01X18166Y-824397D02*
X17696Y-824082D01*
X17148Y-823872D01*
X16521D01*
X15816Y-824187D01*
X15268Y-824712D01*
X14876Y-825342D01*
X14563Y-826392D01*
X14485Y-827337D01*
X14641Y-828282D01*
X14876Y-828912D01*
X15346Y-829542D01*
X15895Y-829962D01*
X16443Y-830172D01*
X16991D01*
X17540Y-829962D01*
X18010Y-829647D01*
X18401Y-829227D01*
G01X21803Y-823872D02*
X23683D01*
G01X22743D02*
Y-830172D01*
G01X21803D02*
X23683D01*
G01X29043Y-823872D02*
Y-830172D01*
G01X27241Y-823872D02*
X30845D01*
G01X35343Y-830172D02*
Y-827337D01*
X33776Y-823872D01*
G01X36910D02*
X35343Y-827337D01*
G01X46220Y-828912D02*
X46690Y-829647D01*
X47316Y-830067D01*
X48021Y-830172D01*
X48648Y-830067D01*
X49275Y-829542D01*
X49666Y-828912D01*
X49745Y-828282D01*
X49588Y-827547D01*
X49040Y-827022D01*
X48491Y-826812D01*
X47786D01*
G01X48491D02*
X48961Y-826497D01*
X49353Y-825972D01*
X49510Y-825342D01*
X49353Y-824712D01*
X48961Y-824187D01*
X48256Y-823872D01*
X47551Y-823977D01*
X46846Y-824397D01*
G01X52520Y-828912D02*
X52990Y-829647D01*
X53616Y-830067D01*
X54321Y-830172D01*
X54948Y-830067D01*
X55575Y-829542D01*
X55966Y-828912D01*
X56045Y-828282D01*
X55888Y-827547D01*
X55340Y-827022D01*
X54791Y-826812D01*
X54086D01*
G01X54791D02*
X55261Y-826497D01*
X55653Y-825972D01*
X55810Y-825342D01*
X55653Y-824712D01*
X55261Y-824187D01*
X54556Y-823872D01*
X53851Y-823977D01*
X53146Y-824397D01*
G01X58820Y-828912D02*
X59290Y-829647D01*
X59916Y-830067D01*
X60621Y-830172D01*
X61248Y-830067D01*
X61875Y-829542D01*
X62266Y-828912D01*
X62345Y-828282D01*
X62188Y-827547D01*
X61640Y-827022D01*
X61091Y-826812D01*
X60386D01*
G01X61091D02*
X61561Y-826497D01*
X61953Y-825972D01*
X62110Y-825342D01*
X61953Y-824712D01*
X61561Y-824187D01*
X60856Y-823872D01*
X60151Y-823977D01*
X59446Y-824397D01*
G01X66686Y-830172D02*
X66843Y-828807D01*
X67078Y-827652D01*
X67391Y-826602D01*
X67783Y-825447D01*
X68410Y-823872D01*
X65276D01*
G01X72986Y-830172D02*
X73143Y-828807D01*
X73378Y-827652D01*
X73691Y-826602D01*
X74083Y-825447D01*
X74710Y-823872D01*
X71576D01*
G01X79286Y-831327D02*
X79600Y-829962D01*
G01X85743Y-823872D02*
Y-830172D01*
G01X83941Y-823872D02*
X87545D01*
G01X90085Y-830172D02*
X92043Y-823872D01*
X94001Y-830172D01*
G01X93296Y-827967D02*
X90790D01*
G01X97403Y-823872D02*
X99283D01*
G01X98343D02*
Y-830172D01*
G01X97403D02*
X99283D01*
G01X102293Y-823872D02*
X103390Y-830172D01*
X104643Y-823872D01*
X105896Y-830172D01*
X106993Y-823872D01*
G01X108985Y-830172D02*
X110943Y-823872D01*
X112901Y-830172D01*
G01X112196Y-827967D02*
X109690D01*
G01X115441Y-830172D02*
Y-823872D01*
X119045Y-830172D01*
Y-823872D01*
G01X129451Y-832272D02*
X128668Y-831222D01*
X128276Y-830172D01*
Y-825972D01*
X128668Y-824922D01*
X129451Y-823872D01*
G01X140876Y-830172D02*
Y-823872D01*
X142835D01*
X143461Y-824187D01*
X143853Y-824607D01*
X144010Y-825447D01*
X143853Y-826287D01*
X143383Y-826812D01*
X142835Y-827127D01*
X140876D01*
G01X142835D02*
X144010Y-830172D01*
G01X148743Y-830382D02*
X148586Y-830277D01*
Y-830067D01*
X148743Y-829962D01*
X148900Y-830067D01*
Y-830277D01*
X148743Y-830382D01*
G01X155043Y-830172D02*
X154416Y-830067D01*
X153868Y-829647D01*
X153398Y-829017D01*
X153085Y-828282D01*
X152928Y-827442D01*
Y-826602D01*
X153085Y-825762D01*
X153398Y-825027D01*
X153868Y-824397D01*
X154416Y-823977D01*
X155043Y-823872D01*
X155670Y-823977D01*
X156218Y-824397D01*
X156688Y-825027D01*
X157001Y-825762D01*
X157158Y-826602D01*
Y-827442D01*
X157001Y-828282D01*
X156688Y-829017D01*
X156218Y-829647D01*
X155670Y-830067D01*
X155043Y-830172D01*
G01X161343Y-830382D02*
X161186Y-830277D01*
Y-830067D01*
X161343Y-829962D01*
X161500Y-830067D01*
Y-830277D01*
X161343Y-830382D01*
G01X169366Y-824397D02*
X168896Y-824082D01*
X168348Y-823872D01*
X167721D01*
X167016Y-824187D01*
X166468Y-824712D01*
X166076Y-825342D01*
X165763Y-826392D01*
X165685Y-827337D01*
X165841Y-828282D01*
X166076Y-828912D01*
X166546Y-829542D01*
X167095Y-829962D01*
X167643Y-830172D01*
X168191D01*
X168740Y-829962D01*
X169210Y-829647D01*
X169601Y-829227D01*
G01X173943Y-830382D02*
X173786Y-830277D01*
Y-830067D01*
X173943Y-829962D01*
X174100Y-830067D01*
Y-830277D01*
X173943Y-830382D01*
G01X180635Y-832272D02*
X181418Y-831222D01*
X181810Y-830172D01*
Y-825972D01*
X181418Y-824922D01*
X180635Y-823872D01*
G01X38743Y-799472D02*
X36223Y-799055D01*
X34018Y-797389D01*
X32128Y-794889D01*
X30868Y-791972D01*
X30238Y-788639D01*
Y-785305D01*
X30868Y-781972D01*
X32128Y-779055D01*
X34018Y-776556D01*
X36223Y-774889D01*
X38743Y-774472D01*
X41263Y-774889D01*
X43468Y-776556D01*
X45358Y-779055D01*
X46618Y-781972D01*
X47248Y-785305D01*
Y-788639D01*
X46618Y-791972D01*
X45358Y-794889D01*
X43468Y-797389D01*
X41263Y-799055D01*
X38743Y-799472D01*
G01X41263Y-792805D02*
X45043Y-799472D01*
G01X58588Y-782806D02*
Y-794472D01*
X59848Y-797389D01*
X61738Y-799055D01*
X63943Y-799472D01*
X66148Y-799055D01*
X68038Y-797389D01*
X69298Y-794472D01*
G01Y-799472D02*
Y-782806D01*
G01X94813Y-799472D02*
Y-782806D01*
G01Y-785722D02*
X93553Y-784056D01*
X91663Y-783222D01*
X89458Y-782806D01*
X87253Y-783639D01*
X85363Y-785305D01*
X84103Y-787806D01*
X83473Y-791139D01*
X84103Y-794472D01*
X85363Y-796973D01*
X87253Y-798639D01*
X89458Y-799472D01*
X91663Y-799055D01*
X93553Y-797806D01*
X94813Y-796139D01*
G01X108988Y-799472D02*
Y-782806D01*
G01Y-786972D02*
X110248Y-784889D01*
X112138Y-783222D01*
X114658Y-782806D01*
X116863Y-783222D01*
X118753Y-784889D01*
X119698Y-787806D01*
Y-799472D01*
G01X139543Y-774472D02*
Y-799472D01*
G01X135133Y-782806D02*
X143953D01*
G01X170413Y-799472D02*
Y-782806D01*
G01Y-785722D02*
X169153Y-784056D01*
X167263Y-783222D01*
X165058Y-782806D01*
X162853Y-783639D01*
X160963Y-785305D01*
X159703Y-787806D01*
X159073Y-791139D01*
X159703Y-794472D01*
X160963Y-796973D01*
X162853Y-798639D01*
X165058Y-799472D01*
X167263Y-799055D01*
X169153Y-797806D01*
X170413Y-796139D01*
G01X14641Y-810172D02*
Y-803872D01*
X18245Y-810172D01*
Y-803872D01*
G01X22743Y-810172D02*
X22116Y-810067D01*
X21568Y-809647D01*
X21098Y-809017D01*
X20785Y-808282D01*
X20628Y-807442D01*
Y-806602D01*
X20785Y-805762D01*
X21098Y-805027D01*
X21568Y-804397D01*
X22116Y-803977D01*
X22743Y-803872D01*
X23370Y-803977D01*
X23918Y-804397D01*
X24388Y-805027D01*
X24701Y-805762D01*
X24858Y-806602D01*
Y-807442D01*
X24701Y-808282D01*
X24388Y-809017D01*
X23918Y-809647D01*
X23370Y-810067D01*
X22743Y-810172D01*
G01X29043Y-810382D02*
X28886Y-810277D01*
Y-810067D01*
X29043Y-809962D01*
X29200Y-810067D01*
Y-810277D01*
X29043Y-810382D01*
G01X33855Y-804922D02*
X34325Y-804292D01*
X34873Y-803977D01*
X35500Y-803872D01*
X36283Y-804082D01*
X36831Y-804607D01*
X36988Y-805237D01*
X36910Y-805867D01*
X36596Y-806392D01*
X35030Y-807442D01*
X34325Y-808177D01*
X33855Y-809227D01*
X33698Y-810172D01*
X36988D01*
G01X41643D02*
Y-803872D01*
X40703Y-805132D01*
G01Y-810172D02*
X42583D01*
G01X47943D02*
Y-803872D01*
X47003Y-805132D01*
G01Y-810172D02*
X48883D01*
G01X54086Y-811327D02*
X54400Y-809962D01*
G01X58193Y-803872D02*
X59290Y-810172D01*
X60543Y-803872D01*
X61796Y-810172D01*
X62893Y-803872D01*
G01X68410Y-810172D02*
X65276D01*
Y-803872D01*
X68410D01*
G01X67156Y-806917D02*
X65276D01*
G01X71341Y-810172D02*
Y-803872D01*
X74945Y-810172D01*
Y-803872D01*
G01X77798Y-810172D02*
Y-803872D01*
G01X81088D02*
Y-810172D01*
G01Y-807022D02*
X77798D01*
G01X84020Y-803872D02*
Y-808387D01*
X84333Y-809332D01*
X84960Y-809962D01*
X85743Y-810172D01*
X86526Y-809962D01*
X87153Y-809332D01*
X87466Y-808387D01*
Y-803872D01*
G01X90085Y-810172D02*
X92043Y-803872D01*
X94001Y-810172D01*
G01X93296Y-807967D02*
X90790D01*
G01X103155Y-804922D02*
X103625Y-804292D01*
X104173Y-803977D01*
X104800Y-803872D01*
X105583Y-804082D01*
X106131Y-804607D01*
X106288Y-805237D01*
X106210Y-805867D01*
X105896Y-806392D01*
X104330Y-807442D01*
X103625Y-808177D01*
X103155Y-809227D01*
X102998Y-810172D01*
X106288D01*
G01X109141D02*
Y-803872D01*
X112745Y-810172D01*
Y-803872D01*
G01X115520Y-810172D02*
Y-803872D01*
X117086D01*
X117713Y-804187D01*
X118183Y-804607D01*
X118575Y-805237D01*
X118888Y-805972D01*
X118966Y-807022D01*
X118888Y-808072D01*
X118575Y-808807D01*
X118183Y-809437D01*
X117713Y-809857D01*
X117086Y-810172D01*
X115520D01*
G01X128276D02*
Y-803872D01*
X130235D01*
X130861Y-804187D01*
X131253Y-804607D01*
X131410Y-805447D01*
X131253Y-806287D01*
X130783Y-806812D01*
X130235Y-807127D01*
X128276D01*
G01X130235D02*
X131410Y-810172D01*
G01X134420D02*
Y-803872D01*
X135986D01*
X136613Y-804187D01*
X137083Y-804607D01*
X137475Y-805237D01*
X137788Y-805972D01*
X137866Y-807022D01*
X137788Y-808072D01*
X137475Y-808807D01*
X137083Y-809437D01*
X136613Y-809857D01*
X135986Y-810172D01*
X134420D01*
G01X142443Y-810382D02*
X142286Y-810277D01*
Y-810067D01*
X142443Y-809962D01*
X142600Y-810067D01*
Y-810277D01*
X142443Y-810382D01*
G01X210093Y-779172D02*
Y-787172D01*
X214093D01*
G01X221893D02*
Y-781839D01*
G01Y-782772D02*
X221493Y-782239D01*
X220893Y-781972D01*
X220193Y-781839D01*
X219493Y-782105D01*
X218893Y-782639D01*
X218493Y-783439D01*
X218293Y-784505D01*
X218493Y-785572D01*
X218893Y-786372D01*
X219493Y-786905D01*
X220193Y-787172D01*
X220893Y-787039D01*
X221493Y-786639D01*
X221893Y-786106D01*
G01X225993Y-789572D02*
X226593Y-789839D01*
X227393Y-789572D01*
X227893Y-789039D01*
X228293Y-788372D01*
X228893Y-786239D01*
X230193Y-781839D01*
G01X226993D02*
X228893Y-786239D01*
G01X234593Y-783572D02*
X237793D01*
X237493Y-782639D01*
X236993Y-782105D01*
X236293Y-781839D01*
X235593Y-781972D01*
X234993Y-782372D01*
X234593Y-783305D01*
X234393Y-784106D01*
Y-784905D01*
X234593Y-785705D01*
X235093Y-786505D01*
X235693Y-787039D01*
X236393Y-787172D01*
X237093Y-786905D01*
X237793Y-786106D01*
G01X242693Y-787172D02*
Y-781839D01*
G01Y-782905D02*
X243193Y-782372D01*
X243693Y-781972D01*
X244393Y-781839D01*
X244893Y-781972D01*
X245493Y-782372D01*
G01X229193Y-829172D02*
X232993D01*
X229193Y-837172D01*
X232993D01*
G01X239093Y-831839D02*
Y-837172D01*
G01Y-829705D02*
X238893Y-829572D01*
Y-829305D01*
X239093Y-829172D01*
X239293Y-829305D01*
Y-829572D01*
X239093Y-829705D01*
G01X245793Y-834505D02*
X248393D01*
G01X253093Y-837172D02*
Y-829172D01*
X255493D01*
X256293Y-829572D01*
X256893Y-830505D01*
X257093Y-831572D01*
X256893Y-832639D01*
X256393Y-833439D01*
X255493Y-833839D01*
X253093D01*
G01X263093Y-831839D02*
Y-837172D01*
G01Y-829705D02*
X262893Y-829572D01*
Y-829305D01*
X263093Y-829172D01*
X263293Y-829305D01*
Y-829572D01*
X263093Y-829705D01*
G01X269393Y-837172D02*
Y-831839D01*
G01Y-833172D02*
X269793Y-832505D01*
X270393Y-831972D01*
X271193Y-831839D01*
X271893Y-831972D01*
X272493Y-832505D01*
X272793Y-833439D01*
Y-837172D01*
G01X277693Y-839172D02*
X278393Y-839705D01*
X279193Y-839839D01*
X279893Y-839705D01*
X280493Y-839039D01*
X280893Y-838105D01*
Y-831839D01*
G01Y-832905D02*
X280493Y-832372D01*
X279893Y-831972D01*
X279193Y-831839D01*
X278393Y-832105D01*
X277893Y-832639D01*
X277493Y-833572D01*
X277293Y-834505D01*
X277393Y-835305D01*
X277793Y-836239D01*
X278393Y-836905D01*
X279193Y-837172D01*
X279793Y-837039D01*
X280493Y-836505D01*
X280893Y-835972D01*
G01X244193Y-808172D02*
X246193D01*
Y-810572D01*
X245593Y-811372D01*
X244893Y-811905D01*
X243893Y-812172D01*
X242893Y-811905D01*
X242193Y-811372D01*
X241593Y-810572D01*
X241193Y-809639D01*
X240993Y-808572D01*
Y-807639D01*
X241193Y-806839D01*
X241593Y-805905D01*
X242193Y-805105D01*
X242793Y-804572D01*
X243593Y-804172D01*
X244293D01*
X245093Y-804439D01*
X245693Y-804972D01*
G01X249293Y-812172D02*
Y-804172D01*
X253893Y-812172D01*
Y-804172D01*
G01X257393Y-812172D02*
Y-804172D01*
X259393D01*
X260193Y-804572D01*
X260793Y-805105D01*
X261293Y-805905D01*
X261693Y-806839D01*
X261793Y-808172D01*
X261693Y-809505D01*
X261293Y-810439D01*
X260793Y-811239D01*
X260193Y-811772D01*
X259393Y-812172D01*
X257393D01*
G01X265693Y-805505D02*
X266293Y-804705D01*
X266993Y-804305D01*
X267793Y-804172D01*
X268793Y-804439D01*
X269493Y-805105D01*
X269693Y-805905D01*
X269593Y-806706D01*
X269193Y-807372D01*
X267193Y-808705D01*
X266293Y-809639D01*
X265693Y-810972D01*
X265493Y-812172D01*
X269693D01*
G01X263393Y-787172D02*
X263593Y-785439D01*
X263893Y-783972D01*
X264293Y-782639D01*
X264793Y-781172D01*
X265593Y-779172D01*
X261593D01*
G01X336693Y-830505D02*
X337293Y-829705D01*
X337993Y-829305D01*
X338793Y-829172D01*
X339793Y-829439D01*
X340493Y-830105D01*
X340693Y-830905D01*
X340593Y-831706D01*
X340193Y-832372D01*
X338193Y-833705D01*
X337293Y-834639D01*
X336693Y-835972D01*
X336493Y-837172D01*
X340693D01*
G01X346593Y-829172D02*
X345793Y-829439D01*
X345193Y-830105D01*
X344793Y-830905D01*
X344493Y-831972D01*
X344393Y-833172D01*
X344493Y-834372D01*
X344793Y-835439D01*
X345193Y-836239D01*
X345793Y-836905D01*
X346593Y-837172D01*
X347393Y-836905D01*
X347993Y-836239D01*
X348393Y-835439D01*
X348693Y-834372D01*
X348793Y-833172D01*
X348693Y-831972D01*
X348393Y-830905D01*
X347993Y-830105D01*
X347393Y-829439D01*
X346593Y-829172D01*
G01X352693Y-830505D02*
X353293Y-829705D01*
X353993Y-829305D01*
X354793Y-829172D01*
X355793Y-829439D01*
X356493Y-830105D01*
X356693Y-830905D01*
X356593Y-831706D01*
X356193Y-832372D01*
X354193Y-833705D01*
X353293Y-834639D01*
X352693Y-835972D01*
X352493Y-837172D01*
X356693D01*
G01X360693Y-830505D02*
X361293Y-829705D01*
X361993Y-829305D01*
X362793Y-829172D01*
X363793Y-829439D01*
X364493Y-830105D01*
X364693Y-830905D01*
X364593Y-831706D01*
X364193Y-832372D01*
X362193Y-833705D01*
X361293Y-834639D01*
X360693Y-835972D01*
X360493Y-837172D01*
X364693D01*
G01X368793Y-837439D02*
X372393Y-829172D01*
G01X378593Y-837172D02*
Y-829172D01*
X377393Y-830772D01*
G01Y-837172D02*
X379793D01*
G01X384693Y-830505D02*
X385293Y-829705D01*
X385993Y-829305D01*
X386793Y-829172D01*
X387793Y-829439D01*
X388493Y-830105D01*
X388693Y-830905D01*
X388593Y-831706D01*
X388193Y-832372D01*
X386193Y-833705D01*
X385293Y-834639D01*
X384693Y-835972D01*
X384493Y-837172D01*
X388693D01*
G01X392793Y-837439D02*
X396393Y-829172D01*
G01X402593D02*
X401793Y-829439D01*
X401193Y-830105D01*
X400793Y-830905D01*
X400493Y-831972D01*
X400393Y-833172D01*
X400493Y-834372D01*
X400793Y-835439D01*
X401193Y-836239D01*
X401793Y-836905D01*
X402593Y-837172D01*
X403393Y-836905D01*
X403993Y-836239D01*
X404393Y-835439D01*
X404693Y-834372D01*
X404793Y-833172D01*
X404693Y-831972D01*
X404393Y-830905D01*
X403993Y-830105D01*
X403393Y-829439D01*
X402593Y-829172D01*
G01X408693Y-830505D02*
X409293Y-829705D01*
X409993Y-829305D01*
X410793Y-829172D01*
X411793Y-829439D01*
X412493Y-830105D01*
X412693Y-830905D01*
X412593Y-831706D01*
X412193Y-832372D01*
X410193Y-833705D01*
X409293Y-834639D01*
X408693Y-835972D01*
X408493Y-837172D01*
X412693D01*
G01X336393Y-814672D02*
Y-806672D01*
X338393D01*
X339193Y-807072D01*
X339793Y-807605D01*
X340293Y-808405D01*
X340693Y-809339D01*
X340793Y-810672D01*
X340693Y-812005D01*
X340293Y-812939D01*
X339793Y-813739D01*
X339193Y-814272D01*
X338393Y-814672D01*
X336393D01*
G01X344093D02*
X346593Y-806672D01*
X349093Y-814672D01*
G01X348193Y-811872D02*
X344993D01*
G01X354593Y-806672D02*
X353793Y-806939D01*
X353193Y-807605D01*
X352793Y-808405D01*
X352493Y-809472D01*
X352393Y-810672D01*
X352493Y-811872D01*
X352793Y-812939D01*
X353193Y-813739D01*
X353793Y-814405D01*
X354593Y-814672D01*
X355393Y-814405D01*
X355993Y-813739D01*
X356393Y-812939D01*
X356693Y-811872D01*
X356793Y-810672D01*
X356693Y-809472D01*
X356393Y-808405D01*
X355993Y-807605D01*
X355393Y-806939D01*
X354593Y-806672D01*
G01X360693Y-814672D02*
Y-806672D01*
X364493D01*
G01X363093Y-810539D02*
X360693D01*
G01X370593Y-806672D02*
X369793Y-806939D01*
X369193Y-807605D01*
X368793Y-808405D01*
X368493Y-809472D01*
X368393Y-810672D01*
X368493Y-811872D01*
X368793Y-812939D01*
X369193Y-813739D01*
X369793Y-814405D01*
X370593Y-814672D01*
X371393Y-814405D01*
X371993Y-813739D01*
X372393Y-812939D01*
X372693Y-811872D01*
X372793Y-810672D01*
X372693Y-809472D01*
X372393Y-808405D01*
X371993Y-807605D01*
X371393Y-806939D01*
X370593Y-806672D01*
G01X378593D02*
Y-814672D01*
G01X376293Y-806672D02*
X380893D01*
G01X384593Y-814672D02*
Y-806672D01*
X386993D01*
X387793Y-807072D01*
X388393Y-808005D01*
X388593Y-809072D01*
X388393Y-810139D01*
X387893Y-810939D01*
X386993Y-811339D01*
X384593D01*
G01X395393Y-810405D02*
X395793Y-810005D01*
X396093Y-809339D01*
X396293Y-808405D01*
X396093Y-807605D01*
X395693Y-807072D01*
X394993Y-806672D01*
X392293D01*
Y-814672D01*
X395593D01*
X396293Y-814139D01*
X396693Y-813339D01*
X396893Y-812405D01*
X396693Y-811472D01*
X396093Y-810672D01*
X395393Y-810405D01*
X392293D01*
G01X400093Y-814672D02*
X402593Y-806672D01*
X405093Y-814672D01*
G01X404193Y-811872D02*
X400993D01*
G01X408693Y-814672D02*
Y-806672D01*
X412493D01*
G01X411093Y-810539D02*
X408693D01*
G01X418593Y-806672D02*
X417793Y-806939D01*
X417193Y-807605D01*
X416793Y-808405D01*
X416493Y-809472D01*
X416393Y-810672D01*
X416493Y-811872D01*
X416793Y-812939D01*
X417193Y-813739D01*
X417793Y-814405D01*
X418593Y-814672D01*
X419393Y-814405D01*
X419993Y-813739D01*
X420393Y-812939D01*
X420693Y-811872D01*
X420793Y-810672D01*
X420693Y-809472D01*
X420393Y-808405D01*
X419993Y-807605D01*
X419393Y-806939D01*
X418593Y-806672D01*
G01X356693Y-787172D02*
Y-779172D01*
X360493D01*
G01X359093Y-783039D02*
X356693D01*
G01X366593Y-779172D02*
X365793Y-779439D01*
X365193Y-780105D01*
X364793Y-780905D01*
X364493Y-781972D01*
X364393Y-783172D01*
X364493Y-784372D01*
X364793Y-785439D01*
X365193Y-786239D01*
X365793Y-786905D01*
X366593Y-787172D01*
X367393Y-786905D01*
X367993Y-786239D01*
X368393Y-785439D01*
X368693Y-784372D01*
X368793Y-783172D01*
X368693Y-781972D01*
X368393Y-780905D01*
X367993Y-780105D01*
X367393Y-779439D01*
X366593Y-779172D01*
G01X374593D02*
Y-787172D01*
G01X372293Y-779172D02*
X376893D01*
G01X379593Y-789839D02*
X385593D01*
G01X388593Y-787172D02*
Y-779172D01*
X390993D01*
X391793Y-779572D01*
X392393Y-780505D01*
X392593Y-781572D01*
X392393Y-782639D01*
X391893Y-783439D01*
X390993Y-783839D01*
X388593D01*
G01X396393Y-787172D02*
Y-779172D01*
X398393D01*
X399193Y-779572D01*
X399793Y-780105D01*
X400293Y-780905D01*
X400693Y-781839D01*
X400793Y-783172D01*
X400693Y-784505D01*
X400293Y-785439D01*
X399793Y-786239D01*
X399193Y-786772D01*
X398393Y-787172D01*
X396393D01*
G01X407393Y-782905D02*
X407793Y-782505D01*
X408093Y-781839D01*
X408293Y-780905D01*
X408093Y-780105D01*
X407693Y-779572D01*
X406993Y-779172D01*
X404293D01*
Y-787172D01*
X407593D01*
X408293Y-786639D01*
X408693Y-785839D01*
X408893Y-784905D01*
X408693Y-783972D01*
X408093Y-783172D01*
X407393Y-782905D01*
X404293D01*
G01X411593Y-789839D02*
X417593D01*
G01X424793Y-779839D02*
X424193Y-779439D01*
X423493Y-779172D01*
X422693D01*
X421793Y-779572D01*
X421093Y-780239D01*
X420593Y-781039D01*
X420193Y-782372D01*
X420093Y-783572D01*
X420293Y-784772D01*
X420593Y-785572D01*
X421193Y-786372D01*
X421893Y-786905D01*
X422593Y-787172D01*
X423293D01*
X423993Y-786905D01*
X424593Y-786505D01*
X425093Y-785972D01*
G01X430593Y-787172D02*
X429793Y-787039D01*
X429093Y-786505D01*
X428493Y-785705D01*
X428093Y-784772D01*
X427893Y-783705D01*
Y-782639D01*
X428093Y-781572D01*
X428493Y-780639D01*
X429093Y-779839D01*
X429793Y-779305D01*
X430593Y-779172D01*
X431393Y-779305D01*
X432093Y-779839D01*
X432693Y-780639D01*
X433093Y-781572D01*
X433293Y-782639D01*
Y-783705D01*
X433093Y-784772D01*
X432693Y-785705D01*
X432093Y-786505D01*
X431393Y-787039D01*
X430593Y-787172D01*
G01X436293D02*
Y-779172D01*
X440893Y-787172D01*
Y-779172D01*
G01X444093D02*
X446593Y-787172D01*
X449093Y-779172D01*
G01X456593Y-787172D02*
X452593D01*
Y-779172D01*
X456593D01*
G01X454993Y-783039D02*
X452593D01*
G01X460593Y-787172D02*
Y-779172D01*
X463093D01*
X463893Y-779572D01*
X464393Y-780105D01*
X464593Y-781172D01*
X464393Y-782239D01*
X463793Y-782905D01*
X463093Y-783305D01*
X460593D01*
G01X463093D02*
X464593Y-787172D01*
G01X470593Y-779172D02*
Y-787172D01*
G01X468293Y-779172D02*
X472893D01*
G01X480593Y-787172D02*
X476593D01*
Y-779172D01*
X480593D01*
G01X478993Y-783039D02*
X476593D01*
G01X484593Y-787172D02*
Y-779172D01*
X487093D01*
X487893Y-779572D01*
X488393Y-780105D01*
X488593Y-781172D01*
X488393Y-782239D01*
X487793Y-782905D01*
X487093Y-783305D01*
X484593D01*
G01X487093D02*
X488593Y-787172D01*
G01X425093Y-840172D02*
Y-832172D01*
X423893Y-833772D01*
G01Y-840172D02*
X426293D01*
G01X431193Y-836839D02*
X431893Y-835905D01*
X432493Y-835372D01*
X433293Y-835105D01*
X433993Y-835372D01*
X434493Y-835905D01*
X434893Y-836705D01*
X434993Y-837639D01*
X434893Y-838439D01*
X434493Y-839239D01*
X433893Y-839905D01*
X433193Y-840172D01*
X432393Y-839905D01*
X431693Y-839106D01*
X431293Y-837905D01*
X431193Y-836572D01*
X431393Y-834839D01*
X431693Y-833905D01*
X432193Y-832972D01*
X432893Y-832305D01*
X433593Y-832172D01*
X434293Y-832439D01*
X434793Y-833105D01*
G01X441093Y-840439D02*
X440893Y-840305D01*
Y-840039D01*
X441093Y-839905D01*
X441293Y-840039D01*
Y-840305D01*
X441093Y-840439D01*
G01X447193Y-836839D02*
X447893Y-835905D01*
X448493Y-835372D01*
X449293Y-835105D01*
X449993Y-835372D01*
X450493Y-835905D01*
X450893Y-836705D01*
X450993Y-837639D01*
X450893Y-838439D01*
X450493Y-839239D01*
X449893Y-839905D01*
X449193Y-840172D01*
X448393Y-839905D01*
X447693Y-839106D01*
X447293Y-837905D01*
X447193Y-836572D01*
X447393Y-834839D01*
X447693Y-833905D01*
X448193Y-832972D01*
X448893Y-832305D01*
X449593Y-832172D01*
X450293Y-832439D01*
X450793Y-833105D01*
G01X470093Y-840172D02*
Y-832172D01*
X468893Y-833772D01*
G01Y-840172D02*
X471293D01*
G01X477893D02*
X478093Y-838439D01*
X478393Y-836972D01*
X478793Y-835639D01*
X479293Y-834172D01*
X480093Y-832172D01*
X476093D01*
G01X486093Y-840439D02*
X485893Y-840305D01*
Y-840039D01*
X486093Y-839905D01*
X486293Y-840039D01*
Y-840305D01*
X486093Y-840439D01*
G01X492193Y-833505D02*
X492793Y-832705D01*
X493493Y-832305D01*
X494293Y-832172D01*
X495293Y-832439D01*
X495993Y-833105D01*
X496193Y-833905D01*
X496093Y-834706D01*
X495693Y-835372D01*
X493693Y-836705D01*
X492793Y-837639D01*
X492193Y-838972D01*
X491993Y-840172D01*
X496193D01*
G01X490193Y-815172D02*
Y-807172D01*
X493993D01*
G01X492593Y-811039D02*
X490193D01*
G54D49*
G01X808871Y270055D02*
X808500Y270426D01*
Y272925D01*
G01X850500Y360075D02*
Y362273D01*
G01X927000Y361075D02*
Y363714D01*
M02*
